FILE_TYPE = MACRO_DRAWING;
SET COLOR_WIRE YELLOW;
SET COLOR_PROP ORANGE;
SET COLOR_DOT WHITE;
SET COLOR_ARC YELLOW;
SET COLOR_BODY GREEN;
SET COLOR_NOTE PURPLE;
SET PROP_DISPLAY VALUE;
SET PAGE_NUMBER P515;
FORCEADD RESISTOR..1
(-10700 6600);
FORCEPROP 1 LAST $LOCATION R226
J 2
(-10801 6655);
DISPLAY 1.212766 (-10801 6655);
PAINT GREEN (-10801 6655);
FORCEPROP 0 LAST CDS_LOCATION R226
J 0
(-10550 6750);
DISPLAY 1.021277 (-10550 6750);
DISPLAY INVISIBLE (-10550 6750);
FORCEPROP 0 LAST $SEC 1
J 0
(-10550 6750);
DISPLAY 0.680851 (-10550 6750);
PAINT MONO (-10550 6750);
DISPLAY INVISIBLE (-10550 6750);
FORCEPROP 0 LAST CDS_SEC 1
J 0
(-10550 6750);
DISPLAY 1.021277 (-10550 6750);
DISPLAY INVISIBLE (-10550 6750);
FORCEPROP 0 LASTPIN (-10800 6600) $PN 1
J 2
(-10810 6610);
DISPLAY 0.680851 (-10810 6610);
PAINT MONO (-10810 6610);
FORCEPROP 0 LASTPIN (-10550 6600) $PN 2
J 0
(-10540 6610);
DISPLAY 0.680851 (-10540 6610);
PAINT MONO (-10540 6610);
FORCEPROP 0 LAST PACKAGE 0402
J 0
(-10750 6700);
DISPLAY 1.021277 (-10750 6700);
FORCEPROP 1 LAST VALUE 330OHM
J 0
(-10550 6650);
DISPLAY 1.212766 (-10550 6650);
PAINT GREEN (-10550 6650);
FORCEPROP 1 LAST PATH I122
J 0
(-10897 6705);
DISPLAY 1.212766 (-10897 6705);
PAINT GREEN (-10897 6705);
DISPLAY INVISIBLE (-10897 6705);
FORCEPROP 1 LAST TOLERANCE 1%
J 0
(-10897 6855);
DISPLAY 1.212766 (-10897 6855);
PAINT GREEN (-10897 6855);
DISPLAY INVISIBLE (-10897 6855);
FORCEPROP 1 LAST CLS_PN G155-13300-01
J 0
(-10836 6800);
DISPLAY 1.212766 (-10836 6800);
PAINT GREEN (-10836 6800);
DISPLAY INVISIBLE (-10836 6800);
FORCEPROP 2 LAST CDS_LIB passive
J 0
(-10700 6600);
DISPLAY INVISIBLE (-10700 6600);
FORCEPROP 1 LAST CDS_LMAN_SYM_OUTLINE -50,50,100,-50
J 0
(-10700 6600);
DISPLAY 0.468085 (-10700 6600);
PAINT GREEN (-10700 6600);
DISPLAY INVISIBLE (-10700 6600);
FORCEADD OFFPAGE_IN..1
(-12150 1150);
FORCEPROP 2 LAST $XR0 25F6<> 
J 0
(-12364 1150);
DISPLAY 0.638298 (-12364 1150);
PAINT MONO (-12364 1150);
FORCEPROP 2 LAST $XR1 30K11> 
J 0
(-12574 1150);
DISPLAY 0.638298 (-12574 1150);
PAINT MONO (-12574 1150);
FORCEPROP 2 LAST $XR2 31D3< 
J 0
(-12754 1150);
DISPLAY 0.638298 (-12754 1150);
PAINT MONO (-12754 1150);
FORCEPROP 2 LAST $XR3 32E2< 
J 0
(-12934 1150);
DISPLAY 0.638298 (-12934 1150);
PAINT MONO (-12934 1150);
FORCEPROP 1 LAST BODY_TYPE COMMENT
J 0
(-12140 1285);
DISPLAY 0.808511 (-12140 1285);
PAINT GREEN (-12140 1285);
DISPLAY INVISIBLE (-12140 1285);
FORCEPROP 1 LAST CDS_LMAN_SYM_OUTLINE -50,50,50,-50
J 0
(-12150 1150);
DISPLAY 0.468085 (-12150 1150);
PAINT GREEN (-12150 1150);
DISPLAY INVISIBLE (-12150 1150);
FORCEPROP 2 LAST CDS_LIB cls
J 0
(-12150 1150);
DISPLAY INVISIBLE (-12150 1150);
FORCEPROP 1 LAST OFFPAGE TRUE
J 0
(-12140 1205);
DISPLAY 0.808511 (-12140 1205);
PAINT GREEN (-12140 1205);
DISPLAY INVISIBLE (-12140 1205);
FORCEPROP 2 LAST PATH I123
J 0
(-12100 1250);
DISPLAY 1.021277 (-12100 1250);
DISPLAY INVISIBLE (-12100 1250);
FORCEADD VCC..1
(-11350 2300);
FORCEPROP 3 LASTPIN (-11300 2250) SIG_NAME XP3R3V\g
J 0
(-11290 2260);
DISPLAY 0.659574 (-11290 2260);
PAINT MONO (-11290 2260);
DISPLAY INVISIBLE (-11290 2260);
FORCEPROP 0 LAST VOLTAGE 3.3
J 0
(-11550 2400);
DISPLAY 1.021277 (-11550 2400);
DISPLAY BOTH (-11550 2400);
FORCEPROP 1 LAST HDL_POWER XP3R3V
J 1
(-11295 2355);
DISPLAY 1.021277 (-11295 2355);
PAINT GREEN (-11295 2355);
FORCEPROP 1 LAST CDS_LMAN_SYM_OUTLINE -250,250,250,-250
J 0
(-11350 2300);
DISPLAY 0.468085 (-11350 2300);
PAINT GREEN (-11350 2300);
DISPLAY INVISIBLE (-11350 2300);
FORCEPROP 2 LAST CDS_LIB cls
J 0
(-11350 2300);
DISPLAY INVISIBLE (-11350 2300);
FORCEPROP 1 LAST BODY_TYPE PLUMBING
J 0
(-11395 2257);
DISPLAY 0.340426 (-11395 2257);
PAINT GREEN (-11395 2257);
DISPLAY INVISIBLE (-11395 2257);
FORCEPROP 1 LAST PATH I124
J 0
(-11315 2390);
DISPLAY 0.808511 (-11315 2390);
PAINT GREEN (-11315 2390);
DISPLAY INVISIBLE (-11315 2390);
FORCEADD GND_SG..1
(-10200 300);
FORCEPROP 3 LASTPIN (-10150 350) SIG_NAME SG\g
J 0
(-10140 360);
DISPLAY 0.659574 (-10140 360);
PAINT MONO (-10140 360);
DISPLAY INVISIBLE (-10140 360);
FORCEPROP 1 LAST HDL_POWER SG
J 1
(-10145 205);
DISPLAY 0.808511 (-10145 205);
PAINT GREEN (-10145 205);
FORCEPROP 2 LAST CDS_LIB cls
J 0
(-10200 300);
DISPLAY INVISIBLE (-10200 300);
FORCEPROP 1 LAST CDS_LMAN_SYM_OUTLINE 0,0,100,-50
J 0
(-10200 300);
DISPLAY 0.468085 (-10200 300);
PAINT GREEN (-10200 300);
DISPLAY INVISIBLE (-10200 300);
FORCEPROP 1 LAST BODY_TYPE PLUMBING
J 0
(-10185 285);
DISPLAY 0.808511 (-10185 285);
PAINT GREEN (-10185 285);
DISPLAY INVISIBLE (-10185 285);
FORCEPROP 1 LAST PATH I126
J 0
(-10165 300);
DISPLAY 0.808511 (-10165 300);
PAINT GREEN (-10165 300);
DISPLAY INVISIBLE (-10165 300);
FORCEADD RESISTOR..2
(-9800 850);
FORCEPROP 1 LAST $LOCATION R227
J 0
(-9750 700);
DISPLAY 1.212766 (-9750 700);
PAINT GREEN (-9750 700);
FORCEPROP 0 LAST CDS_LOCATION R227
J 0
(-9750 1000);
DISPLAY 1.021277 (-9750 1000);
DISPLAY INVISIBLE (-9750 1000);
FORCEPROP 0 LAST $SEC 1
J 0
(-9750 1000);
DISPLAY 0.680851 (-9750 1000);
PAINT MONO (-9750 1000);
DISPLAY INVISIBLE (-9750 1000);
FORCEPROP 0 LAST CDS_SEC 1
J 0
(-9750 1000);
DISPLAY 1.021277 (-9750 1000);
DISPLAY INVISIBLE (-9750 1000);
FORCEPROP 0 LASTPIN (-9800 950) $PN 1
R 1
J 0
(-9810 960);
DISPLAY 0.680851 (-9810 960);
PAINT MONO (-9810 960);
FORCEPROP 0 LASTPIN (-9800 700) $PN 2
R 1
J 2
(-9810 690);
DISPLAY 0.680851 (-9810 690);
PAINT MONO (-9810 690);
FORCEPROP 0 LAST PACKAGE 0402
J 0
(-9750 650);
DISPLAY 1.021277 (-9750 650);
FORCEPROP 0 LAST NO_ASSY TRUE
J 0
(-9900 800);
DISPLAY 1.021277 (-9900 800);
DISPLAY BOTH (-9900 800);
FORCEPROP 1 LAST VALUE 10KOHM
J 0
(-9750 900);
DISPLAY 1.212766 (-9750 900);
PAINT GREEN (-9750 900);
FORCEPROP 1 LAST CLS_PN G155-11002-01
J 0
(-9936 1050);
DISPLAY 1.212766 (-9936 1050);
PAINT GREEN (-9936 1050);
DISPLAY INVISIBLE (-9936 1050);
FORCEPROP 1 LAST CDS_LMAN_SYM_OUTLINE -50,50,50,-100
J 0
(-9800 850);
DISPLAY 0.468085 (-9800 850);
PAINT GREEN (-9800 850);
DISPLAY INVISIBLE (-9800 850);
FORCEPROP 2 LAST CDS_LIB passive
J 0
(-9800 850);
DISPLAY INVISIBLE (-9800 850);
FORCEPROP 1 LAST TOLERANCE 1%
J 0
(-9997 1105);
DISPLAY 1.212766 (-9997 1105);
PAINT GREEN (-9997 1105);
DISPLAY INVISIBLE (-9997 1105);
FORCEPROP 1 LAST PATH I127
J 0
(-9997 955);
DISPLAY 1.212766 (-9997 955);
PAINT GREEN (-9997 955);
DISPLAY INVISIBLE (-9997 955);
FORCEADD CAPACITOR..2
(-9250 800);
FORCEPROP 1 LAST $LOCATION C227
J 0
(-9150 650);
DISPLAY 1.212766 (-9150 650);
PAINT GREEN (-9150 650);
FORCEPROP 0 LAST CDS_LOCATION C227
J 0
(-9200 950);
DISPLAY 1.021277 (-9200 950);
DISPLAY INVISIBLE (-9200 950);
FORCEPROP 0 LAST $SEC 1
J 0
(-9200 950);
DISPLAY 0.680851 (-9200 950);
PAINT MONO (-9200 950);
DISPLAY INVISIBLE (-9200 950);
FORCEPROP 0 LAST CDS_SEC 1
J 0
(-9200 950);
DISPLAY 1.021277 (-9200 950);
DISPLAY INVISIBLE (-9200 950);
FORCEPROP 0 LASTPIN (-9250 900) $PN 1
R 1
J 0
(-9260 910);
DISPLAY 0.680851 (-9260 910);
PAINT MONO (-9260 910);
FORCEPROP 0 LASTPIN (-9250 650) $PN 2
R 1
J 2
(-9260 640);
DISPLAY 0.680851 (-9260 640);
PAINT MONO (-9260 640);
FORCEPROP 0 LAST PACKAGE 0402
J 0
(-9150 750);
DISPLAY 1.021277 (-9150 750);
FORCEPROP 0 LAST VOLTAGE 25V
J 0
(-9150 950);
DISPLAY 1.021277 (-9150 950);
FORCEPROP 1 LAST VALUE 0.1UF
J 0
(-9150 850);
DISPLAY 1.212766 (-9150 850);
PAINT GREEN (-9150 850);
FORCEPROP 1 LAST CLS_PN G105-0B104-EK
J 0
(-9350 850);
DISPLAY 1.212766 (-9350 850);
PAINT GREEN (-9350 850);
DISPLAY INVISIBLE (-9350 850);
FORCEPROP 1 LAST CDS_LMAN_SYM_OUTLINE -50,0,50,-50
J 0
(-9250 800);
DISPLAY 0.468085 (-9250 800);
PAINT GREEN (-9250 800);
DISPLAY INVISIBLE (-9250 800);
FORCEPROP 2 LAST CDS_LIB passive
J 0
(-9250 800);
DISPLAY INVISIBLE (-9250 800);
FORCEPROP 2 LASTPIN (-9250 900) SIG_NAME UN$515$CAPACITOR$I128$1
J 0
(-9240 910);
DISPLAY 0.659574 (-9240 910);
PAINT MONO (-9240 910);
DISPLAY INVISIBLE (-9240 910);
FORCEPROP 1 LAST TOLERANCE 10%
J 0
(-9400 900);
DISPLAY 1.212766 (-9400 900);
PAINT GREEN (-9400 900);
DISPLAY INVISIBLE (-9400 900);
FORCEPROP 1 LAST PATH I128
J 0
(-9350 850);
DISPLAY 1.212766 (-9350 850);
PAINT GREEN (-9350 850);
DISPLAY INVISIBLE (-9350 850);
FORCEADD RESISTOR..2
(-9750 1700);
FORCEPROP 1 LAST $LOCATION R228
J 0
(-10100 1550);
DISPLAY 1.212766 (-10100 1550);
PAINT GREEN (-10100 1550);
FORCEPROP 0 LAST CDS_LOCATION R228
J 0
(-9700 1850);
DISPLAY 1.021277 (-9700 1850);
DISPLAY INVISIBLE (-9700 1850);
FORCEPROP 0 LAST $SEC 1
J 0
(-9700 1850);
DISPLAY 0.680851 (-9700 1850);
PAINT MONO (-9700 1850);
DISPLAY INVISIBLE (-9700 1850);
FORCEPROP 0 LAST CDS_SEC 1
J 0
(-9700 1850);
DISPLAY 1.021277 (-9700 1850);
DISPLAY INVISIBLE (-9700 1850);
FORCEPROP 0 LASTPIN (-9750 1800) $PN 1
R 1
J 0
(-9760 1810);
DISPLAY 0.680851 (-9760 1810);
PAINT MONO (-9760 1810);
FORCEPROP 0 LASTPIN (-9750 1550) $PN 2
R 1
J 2
(-9760 1540);
DISPLAY 0.680851 (-9760 1540);
PAINT MONO (-9760 1540);
FORCEPROP 0 LAST PACKAGE 0402
J 0
(-10100 1850);
DISPLAY 1.021277 (-10100 1850);
FORCEPROP 1 LAST VALUE 1.13KOHM
J 0
(-10300 1650);
DISPLAY 1.212766 (-10300 1650);
PAINT GREEN (-10300 1650);
FORCEPROP 0 LAST NO_ASSY TRUE
J 0
(-10350 1750);
DISPLAY 1.021277 (-10350 1750);
DISPLAY BOTH (-10350 1750);
FORCEPROP 2 LAST CDS_LIB passive
J 0
(-9750 1700);
DISPLAY INVISIBLE (-9750 1700);
FORCEPROP 1 LAST CDS_LMAN_SYM_OUTLINE -50,50,50,-100
J 0
(-9750 1700);
DISPLAY 0.468085 (-9750 1700);
PAINT GREEN (-9750 1700);
DISPLAY INVISIBLE (-9750 1700);
FORCEPROP 1 LAST CLS_PN G152-00055-01
J 0
(-9886 1900);
DISPLAY 1.212766 (-9886 1900);
PAINT GREEN (-9886 1900);
DISPLAY INVISIBLE (-9886 1900);
FORCEPROP 1 LAST TOLERANCE 1%
J 0
(-9947 1955);
DISPLAY 1.212766 (-9947 1955);
PAINT GREEN (-9947 1955);
DISPLAY INVISIBLE (-9947 1955);
FORCEPROP 1 LAST PATH I129
J 0
(-9947 1805);
DISPLAY 1.212766 (-9947 1805);
PAINT GREEN (-9947 1805);
DISPLAY INVISIBLE (-9947 1805);
FORCEADD CAPACITOR..2
(-9300 1850);
FORCEPROP 1 LAST $LOCATION C228
J 0
(-9200 1650);
DISPLAY 1.212766 (-9200 1650);
PAINT GREEN (-9200 1650);
FORCEPROP 0 LAST CDS_LOCATION C228
J 0
(-9250 2000);
DISPLAY 1.021277 (-9250 2000);
DISPLAY INVISIBLE (-9250 2000);
FORCEPROP 0 LAST $SEC 1
J 0
(-9250 2000);
DISPLAY 0.680851 (-9250 2000);
PAINT MONO (-9250 2000);
DISPLAY INVISIBLE (-9250 2000);
FORCEPROP 0 LAST CDS_SEC 1
J 0
(-9250 2000);
DISPLAY 1.021277 (-9250 2000);
DISPLAY INVISIBLE (-9250 2000);
FORCEPROP 0 LASTPIN (-9300 1950) $PN 1
R 1
J 0
(-9310 1960);
DISPLAY 0.680851 (-9310 1960);
PAINT MONO (-9310 1960);
FORCEPROP 0 LASTPIN (-9300 1700) $PN 2
R 1
J 2
(-9310 1690);
DISPLAY 0.680851 (-9310 1690);
PAINT MONO (-9310 1690);
FORCEPROP 0 LAST PACKAGE 0805
J 0
(-9200 1875);
DISPLAY 1.021277 (-9200 1875);
FORCEPROP 0 LAST VOLTAGE 25V
J 0
(-9200 1975);
DISPLAY 1.021277 (-9200 1975);
FORCEPROP 1 LAST VALUE 10UF
J 0
(-9200 1750);
DISPLAY 1.212766 (-9200 1750);
PAINT GREEN (-9200 1750);
FORCEPROP 1 LAST CLS_PN G107-0F106-EM
J 0
(-9400 1900);
DISPLAY 1.212766 (-9400 1900);
PAINT GREEN (-9400 1900);
DISPLAY INVISIBLE (-9400 1900);
FORCEPROP 1 LAST TOLERANCE 20%
J 0
(-9450 1950);
DISPLAY 1.212766 (-9450 1950);
PAINT GREEN (-9450 1950);
DISPLAY INVISIBLE (-9450 1950);
FORCEPROP 2 LASTPIN (-9300 1950) SIG_NAME UN$515$CAPACITOR$I130$1
J 0
(-9290 1960);
DISPLAY 0.659574 (-9290 1960);
PAINT MONO (-9290 1960);
DISPLAY INVISIBLE (-9290 1960);
FORCEPROP 2 LAST CDS_LIB passive
J 0
(-9300 1850);
DISPLAY INVISIBLE (-9300 1850);
FORCEPROP 1 LAST CDS_LMAN_SYM_OUTLINE -50,0,50,-50
J 0
(-9300 1850);
DISPLAY 0.468085 (-9300 1850);
PAINT GREEN (-9300 1850);
DISPLAY INVISIBLE (-9300 1850);
FORCEPROP 1 LAST PATH I130
J 0
(-9400 1900);
DISPLAY 1.212766 (-9400 1900);
PAINT GREEN (-9400 1900);
DISPLAY INVISIBLE (-9400 1900);
FORCEADD GND_SG..1
(-8800 250);
FORCEPROP 3 LASTPIN (-8750 300) SIG_NAME SG\g
J 0
(-8740 310);
DISPLAY 0.659574 (-8740 310);
PAINT MONO (-8740 310);
DISPLAY INVISIBLE (-8740 310);
FORCEPROP 2 LAST VOLTAGE 0
J 0
(-8700 200);
DISPLAY 1.021277 (-8700 200);
FORCEPROP 1 LAST HDL_POWER SG
J 1
(-8745 155);
DISPLAY 0.808511 (-8745 155);
PAINT GREEN (-8745 155);
FORCEPROP 2 LAST CDS_LIB cls
J 0
(-8800 250);
DISPLAY INVISIBLE (-8800 250);
FORCEPROP 1 LAST CDS_LMAN_SYM_OUTLINE 0,0,100,-50
J 0
(-8800 250);
DISPLAY 0.468085 (-8800 250);
PAINT GREEN (-8800 250);
DISPLAY INVISIBLE (-8800 250);
FORCEPROP 1 LAST BODY_TYPE PLUMBING
J 0
(-8785 235);
DISPLAY 0.808511 (-8785 235);
PAINT GREEN (-8785 235);
DISPLAY INVISIBLE (-8785 235);
FORCEPROP 1 LAST PATH I131
J 0
(-8765 250);
DISPLAY 0.808511 (-8765 250);
PAINT GREEN (-8765 250);
DISPLAY INVISIBLE (-8765 250);
FORCEADD CAPACITOR..2
(-8750 650);
FORCEPROP 1 LAST $LOCATION C231
J 0
(-8650 450);
DISPLAY 1.212766 (-8650 450);
PAINT GREEN (-8650 450);
FORCEPROP 0 LAST CDS_LOCATION C231
J 0
(-8650 700);
DISPLAY 1.021277 (-8650 700);
DISPLAY INVISIBLE (-8650 700);
FORCEPROP 0 LAST $SEC 1
J 0
(-8650 700);
DISPLAY 0.680851 (-8650 700);
PAINT MONO (-8650 700);
DISPLAY INVISIBLE (-8650 700);
FORCEPROP 0 LAST CDS_SEC 1
J 0
(-8650 700);
DISPLAY 1.021277 (-8650 700);
DISPLAY INVISIBLE (-8650 700);
FORCEPROP 0 LASTPIN (-8750 750) $PN 1
R 1
J 0
(-8760 760);
DISPLAY 0.680851 (-8760 760);
PAINT MONO (-8760 760);
FORCEPROP 0 LASTPIN (-8750 500) $PN 2
R 1
J 2
(-8760 490);
DISPLAY 0.680851 (-8760 490);
PAINT MONO (-8760 490);
FORCEPROP 0 LAST PACKAGE 0201
J 0
(-8650 650);
DISPLAY 1.021277 (-8650 650);
FORCEPROP 1 LAST VALUE 0.01UF
J 0
(-8650 550);
DISPLAY 0.978723 (-8650 550);
PAINT GREEN (-8650 550);
FORCEPROP 0 LAST VOLTAGE 25V
J 0
(-8650 750);
DISPLAY 1.021277 (-8650 750);
FORCEPROP 1 LAST CLS_PN G104-0B103-EK
J 0
(-8850 700);
DISPLAY 1.212766 (-8850 700);
PAINT GREEN (-8850 700);
DISPLAY INVISIBLE (-8850 700);
FORCEPROP 1 LAST TOLERANCE 10%
J 0
(-8900 750);
DISPLAY 1.212766 (-8900 750);
PAINT GREEN (-8900 750);
DISPLAY INVISIBLE (-8900 750);
FORCEPROP 2 LASTPIN (-8750 750) SIG_NAME UN$515$CAPACITOR$I132$1
J 0
(-8740 760);
DISPLAY 0.659574 (-8740 760);
PAINT MONO (-8740 760);
DISPLAY INVISIBLE (-8740 760);
FORCEPROP 2 LAST CDS_LIB passive
J 0
(-8750 650);
DISPLAY INVISIBLE (-8750 650);
FORCEPROP 1 LAST CDS_LMAN_SYM_OUTLINE -50,0,50,-50
J 0
(-8750 650);
DISPLAY 0.468085 (-8750 650);
PAINT GREEN (-8750 650);
DISPLAY INVISIBLE (-8750 650);
FORCEPROP 1 LAST PATH I132
J 0
(-8850 700);
DISPLAY 1.212766 (-8850 700);
PAINT GREEN (-8850 700);
DISPLAY INVISIBLE (-8850 700);
FORCEADD GND_SG..1
(-8900 1400);
FORCEPROP 3 LASTPIN (-8850 1450) SIG_NAME SG\g
J 0
(-8840 1460);
DISPLAY 0.659574 (-8840 1460);
PAINT MONO (-8840 1460);
DISPLAY INVISIBLE (-8840 1460);
FORCEPROP 2 LAST VOLTAGE 0
J 0
(-8800 1350);
DISPLAY 1.021277 (-8800 1350);
FORCEPROP 1 LAST HDL_POWER SG
J 1
(-8845 1305);
DISPLAY 0.808511 (-8845 1305);
PAINT GREEN (-8845 1305);
FORCEPROP 2 LAST CDS_LIB cls
J 0
(-8900 1400);
DISPLAY INVISIBLE (-8900 1400);
FORCEPROP 1 LAST CDS_LMAN_SYM_OUTLINE 0,0,100,-50
J 0
(-8900 1400);
DISPLAY 0.468085 (-8900 1400);
PAINT GREEN (-8900 1400);
DISPLAY INVISIBLE (-8900 1400);
FORCEPROP 1 LAST BODY_TYPE PLUMBING
J 0
(-8885 1385);
DISPLAY 0.808511 (-8885 1385);
PAINT GREEN (-8885 1385);
DISPLAY INVISIBLE (-8885 1385);
FORCEPROP 1 LAST PATH I133
J 0
(-8865 1400);
DISPLAY 0.808511 (-8865 1400);
PAINT GREEN (-8865 1400);
DISPLAY INVISIBLE (-8865 1400);
FORCEADD CAPACITOR..2
(-8850 1850);
FORCEPROP 1 LAST $LOCATION C230
J 0
(-8750 1650);
DISPLAY 1.212766 (-8750 1650);
PAINT GREEN (-8750 1650);
FORCEPROP 0 LAST CDS_LOCATION C230
J 0
(-8800 2000);
DISPLAY 1.021277 (-8800 2000);
DISPLAY INVISIBLE (-8800 2000);
FORCEPROP 0 LAST $SEC 1
J 0
(-8800 2000);
DISPLAY 0.680851 (-8800 2000);
PAINT MONO (-8800 2000);
DISPLAY INVISIBLE (-8800 2000);
FORCEPROP 0 LAST CDS_SEC 1
J 0
(-8800 2000);
DISPLAY 1.021277 (-8800 2000);
DISPLAY INVISIBLE (-8800 2000);
FORCEPROP 0 LASTPIN (-8850 1950) $PN 1
R 1
J 0
(-8860 1960);
DISPLAY 0.680851 (-8860 1960);
PAINT MONO (-8860 1960);
FORCEPROP 0 LASTPIN (-8850 1700) $PN 2
R 1
J 2
(-8860 1690);
DISPLAY 0.680851 (-8860 1690);
PAINT MONO (-8860 1690);
FORCEPROP 0 LAST PACKAGE 0402
J 0
(-8750 1850);
DISPLAY 1.021277 (-8750 1850);
FORCEPROP 0 LAST VOLTAGE 25V
J 0
(-8750 1950);
DISPLAY 1.021277 (-8750 1950);
FORCEPROP 1 LAST VALUE 0.1UF
J 0
(-8750 1750);
DISPLAY 1.212766 (-8750 1750);
PAINT GREEN (-8750 1750);
FORCEPROP 1 LAST TOLERANCE 10%
J 0
(-9000 1950);
DISPLAY 1.212766 (-9000 1950);
PAINT GREEN (-9000 1950);
DISPLAY INVISIBLE (-9000 1950);
FORCEPROP 2 LAST CDS_LIB passive
J 0
(-8850 1850);
DISPLAY INVISIBLE (-8850 1850);
FORCEPROP 1 LAST CDS_LMAN_SYM_OUTLINE -50,0,50,-50
J 0
(-8850 1850);
DISPLAY 0.468085 (-8850 1850);
PAINT GREEN (-8850 1850);
DISPLAY INVISIBLE (-8850 1850);
FORCEPROP 1 LAST CLS_PN G105-0B104-EK
J 0
(-8950 1900);
DISPLAY 1.212766 (-8950 1900);
PAINT GREEN (-8950 1900);
DISPLAY INVISIBLE (-8950 1900);
FORCEPROP 1 LAST PATH I134
J 0
(-8950 1900);
DISPLAY 1.212766 (-8950 1900);
PAINT GREEN (-8950 1900);
DISPLAY INVISIBLE (-8950 1900);
FORCEADD FERRITEBEAD..1
(-10550 2200);
FORCEPROP 1 LAST $LOCATION L13
J 2
(-10610 2259);
DISPLAY 1.212766 (-10610 2259);
PAINT GREEN (-10610 2259);
FORCEPROP 0 LAST CDS_LOCATION L13
J 0
(-10250 2350);
DISPLAY 1.021277 (-10250 2350);
DISPLAY INVISIBLE (-10250 2350);
FORCEPROP 0 LAST $SEC 1
J 0
(-10250 2350);
DISPLAY 0.680851 (-10250 2350);
PAINT MONO (-10250 2350);
DISPLAY INVISIBLE (-10250 2350);
FORCEPROP 0 LAST CDS_SEC 1
J 0
(-10250 2350);
DISPLAY 1.021277 (-10250 2350);
DISPLAY INVISIBLE (-10250 2350);
FORCEPROP 0 LASTPIN (-10650 2150) $PN 1
J 2
(-10660 2160);
DISPLAY 0.680851 (-10660 2160);
PAINT MONO (-10660 2160);
FORCEPROP 0 LASTPIN (-10250 2150) $PN 2
J 0
(-10240 2160);
DISPLAY 0.680851 (-10240 2160);
PAINT MONO (-10240 2160);
FORCEPROP 0 LAST PACKAGE 0603
J 0
(-10550 2250);
DISPLAY 1.021277 (-10550 2250);
FORCEPROP 1 LAST VALUE 26OHM
J 0
(-10250 2250);
DISPLAY 1.212766 (-10250 2250);
PAINT GREEN (-10250 2250);
FORCEPROP 2 LAST CDS_LIB passive
J 0
(-10550 2200);
DISPLAY INVISIBLE (-10550 2200);
FORCEPROP 1 LAST CDS_LMAN_SYM_OUTLINE 0,0,200,-100
J 0
(-10550 2200);
DISPLAY 0.468085 (-10550 2200);
PAINT GREEN (-10550 2200);
DISPLAY INVISIBLE (-10550 2200);
FORCEPROP 1 LAST CLS_PN G191-10101-01
J 2
(-10600 2250);
DISPLAY 1.212766 (-10600 2250);
PAINT GREEN (-10600 2250);
DISPLAY INVISIBLE (-10600 2250);
FORCEPROP 1 LAST PATH I135
J 2
(-10600 2250);
DISPLAY 1.212766 (-10600 2250);
PAINT GREEN (-10600 2250);
DISPLAY INVISIBLE (-10600 2250);
FORCEPROP 1 LAST TOLERANCE 25%
J 0
(-10650 2250);
DISPLAY 1.212766 (-10650 2250);
PAINT GREEN (-10650 2250);
DISPLAY INVISIBLE (-10650 2250);
FORCEADD GND_SG..1
(-6700 100);
FORCEPROP 3 LASTPIN (-6650 150) SIG_NAME SG\g
J 0
(-6640 160);
DISPLAY 0.659574 (-6640 160);
PAINT MONO (-6640 160);
DISPLAY INVISIBLE (-6640 160);
FORCEPROP 2 LAST VOLTAGE 0
J 0
(-6600 50);
DISPLAY 1.021277 (-6600 50);
FORCEPROP 1 LAST HDL_POWER SG
J 1
(-6645 5);
DISPLAY 0.808511 (-6645 5);
PAINT GREEN (-6645 5);
FORCEPROP 2 LAST CDS_LIB cls
J 0
(-6700 100);
DISPLAY INVISIBLE (-6700 100);
FORCEPROP 1 LAST CDS_LMAN_SYM_OUTLINE 0,0,100,-50
J 0
(-6700 100);
DISPLAY 0.468085 (-6700 100);
PAINT GREEN (-6700 100);
DISPLAY INVISIBLE (-6700 100);
FORCEPROP 1 LAST BODY_TYPE PLUMBING
J 0
(-6685 85);
DISPLAY 0.808511 (-6685 85);
PAINT GREEN (-6685 85);
DISPLAY INVISIBLE (-6685 85);
FORCEPROP 1 LAST PATH I136
J 0
(-6665 100);
DISPLAY 0.808511 (-6665 100);
PAINT GREEN (-6665 100);
DISPLAY INVISIBLE (-6665 100);
FORCEADD GND_SG..1
(-5850 -200);
FORCEPROP 3 LASTPIN (-5800 -150) SIG_NAME SG\g
J 0
(-5790 -140);
DISPLAY 0.659574 (-5790 -140);
PAINT MONO (-5790 -140);
DISPLAY INVISIBLE (-5790 -140);
FORCEPROP 2 LAST VOLTAGE 0
J 0
(-5750 -250);
DISPLAY 1.021277 (-5750 -250);
FORCEPROP 1 LAST HDL_POWER SG
J 1
(-5795 -295);
DISPLAY 0.808511 (-5795 -295);
PAINT GREEN (-5795 -295);
FORCEPROP 1 LAST CDS_LMAN_SYM_OUTLINE 0,0,100,-50
J 0
(-5850 -200);
DISPLAY 0.468085 (-5850 -200);
PAINT GREEN (-5850 -200);
DISPLAY INVISIBLE (-5850 -200);
FORCEPROP 2 LAST CDS_LIB cls
J 0
(-5850 -200);
DISPLAY INVISIBLE (-5850 -200);
FORCEPROP 1 LAST BODY_TYPE PLUMBING
J 0
(-5835 -215);
DISPLAY 0.808511 (-5835 -215);
PAINT GREEN (-5835 -215);
DISPLAY INVISIBLE (-5835 -215);
FORCEPROP 1 LAST PATH I137
J 0
(-5815 -200);
DISPLAY 0.808511 (-5815 -200);
PAINT GREEN (-5815 -200);
DISPLAY INVISIBLE (-5815 -200);
FORCEADD CAPACITOR..2
(-5800 50);
FORCEPROP 1 LAST $LOCATION C234
J 0
(-5650 -150);
DISPLAY 1.212766 (-5650 -150);
PAINT GREEN (-5650 -150);
FORCEPROP 0 LAST CDS_LOCATION C234
J 0
(-5700 100);
DISPLAY 1.021277 (-5700 100);
DISPLAY INVISIBLE (-5700 100);
FORCEPROP 0 LAST $SEC 1
J 0
(-5700 100);
DISPLAY 0.680851 (-5700 100);
PAINT MONO (-5700 100);
DISPLAY INVISIBLE (-5700 100);
FORCEPROP 0 LAST CDS_SEC 1
J 0
(-5700 100);
DISPLAY 1.021277 (-5700 100);
DISPLAY INVISIBLE (-5700 100);
FORCEPROP 0 LASTPIN (-5800 150) $PN 1
R 1
J 0
(-5810 160);
DISPLAY 0.680851 (-5810 160);
PAINT MONO (-5810 160);
FORCEPROP 0 LASTPIN (-5800 -100) $PN 2
R 1
J 2
(-5810 -110);
DISPLAY 0.680851 (-5810 -110);
PAINT MONO (-5810 -110);
FORCEPROP 1 LAST VALUE 0.01UF
J 0
(-5650 -50);
DISPLAY 0.978723 (-5650 -50);
PAINT GREEN (-5650 -50);
FORCEPROP 0 LAST PACKAGE 0201
J 0
(-5650 50);
DISPLAY 1.021277 (-5650 50);
FORCEPROP 0 LAST VOLTAGE 25V
J 0
(-5650 150);
DISPLAY 1.021277 (-5650 150);
FORCEPROP 1 LAST CLS_PN G104-0B103-EK
J 0
(-5900 100);
DISPLAY 1.212766 (-5900 100);
PAINT GREEN (-5900 100);
DISPLAY INVISIBLE (-5900 100);
FORCEPROP 1 LAST TOLERANCE 10%
J 0
(-5950 150);
DISPLAY 1.212766 (-5950 150);
PAINT GREEN (-5950 150);
DISPLAY INVISIBLE (-5950 150);
FORCEPROP 1 LAST CDS_LMAN_SYM_OUTLINE -50,0,50,-50
J 0
(-5800 50);
DISPLAY 0.468085 (-5800 50);
PAINT GREEN (-5800 50);
DISPLAY INVISIBLE (-5800 50);
FORCEPROP 2 LAST CDS_LIB passive
J 0
(-5800 50);
DISPLAY INVISIBLE (-5800 50);
FORCEPROP 2 LASTPIN (-5800 150) SIG_NAME UN$515$CAPACITOR$I138$1
J 0
(-5790 160);
DISPLAY 0.659574 (-5790 160);
PAINT MONO (-5790 160);
DISPLAY INVISIBLE (-5790 160);
FORCEPROP 1 LAST PATH I138
J 0
(-5900 100);
DISPLAY 1.212766 (-5900 100);
PAINT GREEN (-5900 100);
DISPLAY INVISIBLE (-5900 100);
FORCEADD RESISTOR..2
(-5750 550);
FORCEPROP 1 LAST $LOCATION R229
J 0
(-5700 500);
DISPLAY 1.212766 (-5700 500);
PAINT GREEN (-5700 500);
FORCEPROP 0 LAST CDS_LOCATION R229
J 0
(-5700 700);
DISPLAY 1.021277 (-5700 700);
DISPLAY INVISIBLE (-5700 700);
FORCEPROP 0 LAST $SEC 1
J 0
(-5700 700);
DISPLAY 0.680851 (-5700 700);
PAINT MONO (-5700 700);
DISPLAY INVISIBLE (-5700 700);
FORCEPROP 0 LAST CDS_SEC 1
J 0
(-5700 700);
DISPLAY 1.021277 (-5700 700);
DISPLAY INVISIBLE (-5700 700);
FORCEPROP 0 LASTPIN (-5750 650) $PN 1
R 1
J 0
(-5760 660);
DISPLAY 0.680851 (-5760 660);
PAINT MONO (-5760 660);
FORCEPROP 0 LASTPIN (-5750 400) $PN 2
R 1
J 2
(-5760 390);
DISPLAY 0.680851 (-5760 390);
PAINT MONO (-5760 390);
FORCEPROP 1 LAST VALUE 4.7KOHM
J 0
(-5700 600);
DISPLAY 1.212766 (-5700 600);
PAINT GREEN (-5700 600);
FORCEPROP 0 LAST PACKAGE 0402
J 0
(-5650 700);
DISPLAY 1.021277 (-5650 700);
FORCEPROP 0 LAST NO_ASSY TRUE
J 0
(-5700 450);
DISPLAY 1.021277 (-5700 450);
DISPLAY BOTH (-5700 450);
FORCEPROP 1 LAST CLS_PN G155-14701-01
J 0
(-5500 600);
DISPLAY 1.212766 (-5500 600);
PAINT GREEN (-5500 600);
DISPLAY INVISIBLE (-5500 600);
FORCEPROP 1 LAST CDS_LMAN_SYM_OUTLINE -50,50,50,-100
J 0
(-5750 550);
DISPLAY 0.468085 (-5750 550);
PAINT GREEN (-5750 550);
DISPLAY INVISIBLE (-5750 550);
FORCEPROP 2 LAST CDS_LIB passive
J 0
(-5750 550);
DISPLAY INVISIBLE (-5750 550);
FORCEPROP 1 LAST TOLERANCE 1%
J 0
(-5500 400);
DISPLAY 1.212766 (-5500 400);
PAINT GREEN (-5500 400);
DISPLAY INVISIBLE (-5500 400);
FORCEPROP 1 LAST PATH I139
J 0
(-5947 655);
DISPLAY 1.212766 (-5947 655);
PAINT GREEN (-5947 655);
DISPLAY INVISIBLE (-5947 655);
FORCEADD RESISTOR..1
(-5050 250);
FORCEPROP 1 LAST $LOCATION R230
J 2
(-5100 300);
DISPLAY 1.212766 (-5100 300);
PAINT GREEN (-5100 300);
FORCEPROP 0 LAST CDS_LOCATION R230
J 0
(-4950 400);
DISPLAY 1.021277 (-4950 400);
DISPLAY INVISIBLE (-4950 400);
FORCEPROP 0 LAST $SEC 1
J 0
(-4950 400);
DISPLAY 0.680851 (-4950 400);
PAINT MONO (-4950 400);
DISPLAY INVISIBLE (-4950 400);
FORCEPROP 0 LAST CDS_SEC 1
J 0
(-4950 400);
DISPLAY 1.021277 (-4950 400);
DISPLAY INVISIBLE (-4950 400);
FORCEPROP 0 LASTPIN (-5150 250) $PN 1
J 2
(-5160 260);
DISPLAY 0.680851 (-5160 260);
PAINT MONO (-5160 260);
FORCEPROP 0 LASTPIN (-4900 250) $PN 2
J 0
(-4890 260);
DISPLAY 0.680851 (-4890 260);
PAINT MONO (-4890 260);
FORCEPROP 1 LAST VALUE 0OHM
J 0
(-4950 300);
DISPLAY 1.212766 (-4950 300);
PAINT GREEN (-4950 300);
FORCEPROP 1 LAST CLS_PN G155-100R0-J0
J 0
(-5186 450);
DISPLAY 1.212766 (-5186 450);
PAINT GREEN (-5186 450);
DISPLAY INVISIBLE (-5186 450);
FORCEPROP 1 LAST CDS_LMAN_SYM_OUTLINE -50,50,100,-50
J 0
(-5050 250);
DISPLAY 0.468085 (-5050 250);
PAINT GREEN (-5050 250);
DISPLAY INVISIBLE (-5050 250);
FORCEPROP 2 LAST CDS_LIB passive
J 0
(-5050 250);
DISPLAY INVISIBLE (-5050 250);
FORCEPROP 1 LAST TOLERANCE -
J 0
(-5247 505);
DISPLAY 1.212766 (-5247 505);
PAINT GREEN (-5247 505);
DISPLAY INVISIBLE (-5247 505);
FORCEPROP 1 LAST PATH I140
J 0
(-5247 355);
DISPLAY 1.212766 (-5247 355);
PAINT GREEN (-5247 355);
DISPLAY INVISIBLE (-5247 355);
FORCEADD OFFPAGE_OUT..1
(-3650 250);
FORCEPROP 2 LAST $XR4 10F12< 
J 0
(-3025 250);
DISPLAY 0.638298 (-3025 250);
PAINT MONO (-3025 250);
FORCEPROP 2 LAST $XR0 24F15> 
J 0
(-3595 250);
DISPLAY 0.638298 (-3595 250);
PAINT MONO (-3595 250);
FORCEPROP 2 LAST $XR1 25C9<> 
J 0
(-3385 250);
DISPLAY 0.638298 (-3385 250);
PAINT MONO (-3385 250);
FORCEPROP 2 LAST $XR2 31D7> 
J 0
(-3205 250);
DISPLAY 0.638298 (-3205 250);
PAINT MONO (-3205 250);
FORCEPROP 2 LAST $XR3 32H7> 
J 0
(-3025 250);
DISPLAY 0.638298 (-3025 250);
PAINT MONO (-3025 250);
FORCEPROP 2 LAST CDS_LIB cls
J 0
(-3650 250);
DISPLAY INVISIBLE (-3650 250);
FORCEPROP 1 LAST CDS_LMAN_SYM_OUTLINE -50,50,50,-50
J 0
(-3650 250);
DISPLAY 0.468085 (-3650 250);
PAINT GREEN (-3650 250);
DISPLAY INVISIBLE (-3650 250);
FORCEPROP 1 LAST BODY_TYPE COMMENT
J 0
(-3640 385);
DISPLAY 0.808511 (-3640 385);
PAINT GREEN (-3640 385);
DISPLAY INVISIBLE (-3640 385);
FORCEPROP 1 LAST OFFPAGE TRUE
J 0
(-3640 305);
DISPLAY 0.808511 (-3640 305);
PAINT GREEN (-3640 305);
DISPLAY INVISIBLE (-3640 305);
FORCEPROP 2 LAST PATH I142
J 0
(-3600 350);
DISPLAY 1.021277 (-3600 350);
DISPLAY INVISIBLE (-3600 350);
FORCEADD RESISTOR..1
R 1
(-4400 1050);
FORCEPROP 1 LAST $LOCATION R232
R 1
J 2
(-4455 949);
DISPLAY 1.212766 (-4455 949);
PAINT GREEN (-4455 949);
FORCEPROP 0 LAST CDS_LOCATION R232
R 1
J 0
(-4350 1250);
DISPLAY 1.021277 (-4350 1250);
DISPLAY INVISIBLE (-4350 1250);
FORCEPROP 0 LAST $SEC 1
R 1
J 0
(-4350 1250);
DISPLAY 0.680851 (-4350 1250);
PAINT MONO (-4350 1250);
DISPLAY INVISIBLE (-4350 1250);
FORCEPROP 0 LAST CDS_SEC 1
R 1
J 0
(-4350 1250);
DISPLAY 1.021277 (-4350 1250);
DISPLAY INVISIBLE (-4350 1250);
FORCEPROP 0 LASTPIN (-4400 950) $PN 1
R 1
J 2
(-4410 940);
DISPLAY 0.680851 (-4410 940);
PAINT MONO (-4410 940);
FORCEPROP 0 LASTPIN (-4400 1200) $PN 2
R 1
J 0
(-4410 1210);
DISPLAY 0.680851 (-4410 1210);
PAINT MONO (-4410 1210);
FORCEPROP 1 LAST VALUE 2.1KOHM
R 1
J 0
(-4305 889);
DISPLAY 1.212766 (-4305 889);
PAINT GREEN (-4305 889);
FORCEPROP 0 LAST PACKAGE 0402
R 1
J 0
(-4350 1300);
DISPLAY 1.021277 (-4350 1300);
FORCEPROP 2 LAST CDS_LIB passive
J 0
(-4400 1050);
DISPLAY INVISIBLE (-4400 1050);
FORCEPROP 1 LAST CDS_LMAN_SYM_OUTLINE -50,50,100,-50
R 1
J 0
(-4400 1050);
DISPLAY 0.468085 (-4400 1050);
PAINT GREEN (-4400 1050);
DISPLAY INVISIBLE (-4400 1050);
FORCEPROP 1 LAST CLS_PN G155-02101-01
R 1
J 0
(-4600 914);
DISPLAY 1.212766 (-4600 914);
PAINT GREEN (-4600 914);
DISPLAY INVISIBLE (-4600 914);
FORCEPROP 1 LAST TOLERANCE 1%
R 1
J 0
(-4655 853);
DISPLAY 1.212766 (-4655 853);
PAINT GREEN (-4655 853);
DISPLAY INVISIBLE (-4655 853);
FORCEPROP 1 LAST PATH I143
R 1
J 0
(-4505 853);
DISPLAY 1.212766 (-4505 853);
PAINT GREEN (-4505 853);
DISPLAY INVISIBLE (-4505 853);
FORCEADD GND_SG..1
(-4200 700);
FORCEPROP 3 LASTPIN (-4150 750) SIG_NAME SG\g
J 0
(-4140 760);
DISPLAY 0.659574 (-4140 760);
PAINT MONO (-4140 760);
DISPLAY INVISIBLE (-4140 760);
FORCEPROP 1 LAST HDL_POWER SG
J 1
(-4150 600);
DISPLAY 0.808511 (-4150 600);
PAINT GREEN (-4150 600);
FORCEPROP 2 LAST CDS_LIB cls
J 0
(-4200 700);
DISPLAY INVISIBLE (-4200 700);
FORCEPROP 1 LAST CDS_LMAN_SYM_OUTLINE 0,0,100,-50
J 0
(-4200 700);
DISPLAY 0.468085 (-4200 700);
PAINT GREEN (-4200 700);
DISPLAY INVISIBLE (-4200 700);
FORCEPROP 1 LAST BODY_TYPE PLUMBING
J 0
(-4185 685);
DISPLAY 0.808511 (-4185 685);
PAINT GREEN (-4185 685);
DISPLAY INVISIBLE (-4185 685);
FORCEPROP 1 LAST PATH I144
J 0
(-4165 700);
DISPLAY 0.808511 (-4165 700);
PAINT GREEN (-4165 700);
DISPLAY INVISIBLE (-4165 700);
FORCEADD RESISTOR..1
R 1
(-4150 1050);
FORCEPROP 1 LAST $LOCATION R233
R 1
J 2
(-4205 949);
DISPLAY 1.212766 (-4205 949);
PAINT GREEN (-4205 949);
FORCEPROP 0 LAST CDS_LOCATION R233
R 1
J 0
(-4100 1250);
DISPLAY 1.021277 (-4100 1250);
DISPLAY INVISIBLE (-4100 1250);
FORCEPROP 0 LAST $SEC 1
R 1
J 0
(-4100 1250);
DISPLAY 0.680851 (-4100 1250);
PAINT MONO (-4100 1250);
DISPLAY INVISIBLE (-4100 1250);
FORCEPROP 0 LAST CDS_SEC 1
R 1
J 0
(-4100 1250);
DISPLAY 1.021277 (-4100 1250);
DISPLAY INVISIBLE (-4100 1250);
FORCEPROP 0 LASTPIN (-4150 950) $PN 1
R 1
J 2
(-4160 940);
DISPLAY 0.680851 (-4160 940);
PAINT MONO (-4160 940);
FORCEPROP 0 LASTPIN (-4150 1200) $PN 2
R 1
J 0
(-4160 1210);
DISPLAY 0.680851 (-4160 1210);
PAINT MONO (-4160 1210);
FORCEPROP 0 LAST PACKAGE 0402
R 1
J 0
(-4100 1300);
DISPLAY 1.021277 (-4100 1300);
FORCEPROP 1 LAST VALUE 2.1KOHM
R 1
J 0
(-4055 889);
DISPLAY 1.212766 (-4055 889);
PAINT GREEN (-4055 889);
FORCEPROP 1 LAST CLS_PN G155-02101-01
R 1
J 0
(-4350 914);
DISPLAY 1.212766 (-4350 914);
PAINT GREEN (-4350 914);
DISPLAY INVISIBLE (-4350 914);
FORCEPROP 1 LAST CDS_LMAN_SYM_OUTLINE -50,50,100,-50
R 1
J 0
(-4150 1050);
DISPLAY 0.468085 (-4150 1050);
PAINT GREEN (-4150 1050);
DISPLAY INVISIBLE (-4150 1050);
FORCEPROP 2 LAST CDS_LIB passive
J 0
(-4150 1050);
DISPLAY INVISIBLE (-4150 1050);
FORCEPROP 1 LAST TOLERANCE 1%
R 1
J 0
(-4405 853);
DISPLAY 1.212766 (-4405 853);
PAINT GREEN (-4405 853);
DISPLAY INVISIBLE (-4405 853);
FORCEPROP 1 LAST PATH I145
R 1
J 0
(-4255 853);
DISPLAY 1.212766 (-4255 853);
PAINT GREEN (-4255 853);
DISPLAY INVISIBLE (-4255 853);
FORCEADD RESISTOR..2
(-4450 1750);
FORCEPROP 1 LAST $LOCATION R231
J 0
(-4400 1550);
DISPLAY 1.212766 (-4400 1550);
PAINT GREEN (-4400 1550);
FORCEPROP 0 LAST CDS_LOCATION R231
J 0
(-4400 1750);
DISPLAY 1.021277 (-4400 1750);
DISPLAY INVISIBLE (-4400 1750);
FORCEPROP 0 LAST $SEC 1
J 0
(-4400 1750);
DISPLAY 0.680851 (-4400 1750);
PAINT MONO (-4400 1750);
DISPLAY INVISIBLE (-4400 1750);
FORCEPROP 0 LAST CDS_SEC 1
J 0
(-4400 1750);
DISPLAY 1.021277 (-4400 1750);
DISPLAY INVISIBLE (-4400 1750);
FORCEPROP 0 LASTPIN (-4450 1850) $PN 1
R 1
J 0
(-4460 1860);
DISPLAY 0.680851 (-4460 1860);
PAINT MONO (-4460 1860);
FORCEPROP 0 LASTPIN (-4450 1600) $PN 2
R 1
J 2
(-4460 1590);
DISPLAY 0.680851 (-4460 1590);
PAINT MONO (-4460 1590);
FORCEPROP 1 LAST VALUE 4.22KOHM
J 0
(-4400 1700);
DISPLAY 0.978723 (-4400 1700);
PAINT GREEN (-4400 1700);
FORCEPROP 0 LAST PACKAGE 0402
J 0
(-4400 1800);
DISPLAY 1.021277 (-4400 1800);
FORCEPROP 1 LAST TOLERANCE 1%
J 0
(-4400 1650);
DISPLAY 0.978723 (-4400 1650);
PAINT GREEN (-4400 1650);
FORCEPROP 2 LAST CDS_LIB passive
J 0
(-4450 1750);
DISPLAY INVISIBLE (-4450 1750);
FORCEPROP 1 LAST CDS_LMAN_SYM_OUTLINE -50,50,50,-100
J 0
(-4450 1750);
DISPLAY 0.468085 (-4450 1750);
PAINT GREEN (-4450 1750);
DISPLAY INVISIBLE (-4450 1750);
FORCEPROP 1 LAST CLS_PN G155-04221-01
J 0
(-4586 1950);
DISPLAY 1.212766 (-4586 1950);
PAINT GREEN (-4586 1950);
DISPLAY INVISIBLE (-4586 1950);
FORCEPROP 1 LAST PATH I146
J 0
(-4647 1855);
DISPLAY 1.212766 (-4647 1855);
PAINT GREEN (-4647 1855);
DISPLAY INVISIBLE (-4647 1855);
FORCEADD CAPACITOR..2
(-3800 1750);
FORCEPROP 1 LAST $LOCATION C239
J 0
(-3700 1550);
DISPLAY 1.212766 (-3700 1550);
PAINT GREEN (-3700 1550);
FORCEPROP 0 LAST CDS_LOCATION C239
J 0
(-3750 1900);
DISPLAY 1.021277 (-3750 1900);
DISPLAY INVISIBLE (-3750 1900);
FORCEPROP 0 LAST $SEC 1
J 0
(-3750 1900);
DISPLAY 0.680851 (-3750 1900);
PAINT MONO (-3750 1900);
DISPLAY INVISIBLE (-3750 1900);
FORCEPROP 0 LAST CDS_SEC 1
J 0
(-3750 1900);
DISPLAY 1.021277 (-3750 1900);
DISPLAY INVISIBLE (-3750 1900);
FORCEPROP 0 LASTPIN (-3800 1850) $PN 1
R 1
J 0
(-3810 1860);
DISPLAY 0.680851 (-3810 1860);
PAINT MONO (-3810 1860);
FORCEPROP 0 LASTPIN (-3800 1600) $PN 2
R 1
J 2
(-3810 1590);
DISPLAY 0.680851 (-3810 1590);
PAINT MONO (-3810 1590);
FORCEPROP 0 LAST VOLTAGE 25V
J 0
(-3700 1850);
DISPLAY 1.021277 (-3700 1850);
FORCEPROP 1 LAST VALUE 10UF
J 0
(-3700 1650);
DISPLAY 1.212766 (-3700 1650);
PAINT GREEN (-3700 1650);
FORCEPROP 0 LAST PACKAGE 0805
J 0
(-3700 1750);
DISPLAY 1.021277 (-3700 1750);
FORCEPROP 1 LAST CLS_PN G107-0F106-EM
J 0
(-3900 1800);
DISPLAY 1.212766 (-3900 1800);
PAINT GREEN (-3900 1800);
DISPLAY INVISIBLE (-3900 1800);
FORCEPROP 1 LAST TOLERANCE 20%
J 0
(-3950 1850);
DISPLAY 1.212766 (-3950 1850);
PAINT GREEN (-3950 1850);
DISPLAY INVISIBLE (-3950 1850);
FORCEPROP 2 LAST CDS_LIB passive
J 0
(-3800 1750);
DISPLAY INVISIBLE (-3800 1750);
FORCEPROP 1 LAST CDS_LMAN_SYM_OUTLINE -50,0,50,-50
J 0
(-3800 1750);
DISPLAY 0.468085 (-3800 1750);
PAINT GREEN (-3800 1750);
DISPLAY INVISIBLE (-3800 1750);
FORCEPROP 1 LAST PATH I147
J 0
(-3900 1800);
DISPLAY 1.212766 (-3900 1800);
PAINT GREEN (-3900 1800);
DISPLAY INVISIBLE (-3900 1800);
FORCEADD GND_SG..1
(-3250 1100);
FORCEPROP 3 LASTPIN (-3200 1150) SIG_NAME SG\g
J 0
(-3190 1160);
DISPLAY 0.659574 (-3190 1160);
PAINT MONO (-3190 1160);
DISPLAY INVISIBLE (-3190 1160);
FORCEPROP 1 LAST HDL_POWER SG
J 1
(-3200 950);
DISPLAY 0.808511 (-3200 950);
PAINT GREEN (-3200 950);
FORCEPROP 2 LAST CDS_LIB cls
J 0
(-3250 1100);
DISPLAY INVISIBLE (-3250 1100);
FORCEPROP 1 LAST CDS_LMAN_SYM_OUTLINE 0,0,100,-50
J 0
(-3250 1100);
DISPLAY 0.468085 (-3250 1100);
PAINT GREEN (-3250 1100);
DISPLAY INVISIBLE (-3250 1100);
FORCEPROP 1 LAST BODY_TYPE PLUMBING
J 0
(-3235 1085);
DISPLAY 0.808511 (-3235 1085);
PAINT GREEN (-3235 1085);
DISPLAY INVISIBLE (-3235 1085);
FORCEPROP 1 LAST PATH I148
J 0
(-3215 1100);
DISPLAY 0.808511 (-3215 1100);
PAINT GREEN (-3215 1100);
DISPLAY INVISIBLE (-3215 1100);
FORCEADD CAPACITOR..2
(-3200 1750);
FORCEPROP 1 LAST $LOCATION C242
J 0
(-3100 1550);
DISPLAY 1.212766 (-3100 1550);
PAINT GREEN (-3100 1550);
FORCEPROP 0 LAST CDS_LOCATION C242
J 0
(-3150 1900);
DISPLAY 1.021277 (-3150 1900);
DISPLAY INVISIBLE (-3150 1900);
FORCEPROP 0 LAST $SEC 1
J 0
(-3150 1900);
DISPLAY 0.680851 (-3150 1900);
PAINT MONO (-3150 1900);
DISPLAY INVISIBLE (-3150 1900);
FORCEPROP 0 LAST CDS_SEC 1
J 0
(-3150 1900);
DISPLAY 1.021277 (-3150 1900);
DISPLAY INVISIBLE (-3150 1900);
FORCEPROP 0 LASTPIN (-3200 1850) $PN 1
R 1
J 0
(-3210 1860);
DISPLAY 0.680851 (-3210 1860);
PAINT MONO (-3210 1860);
FORCEPROP 0 LASTPIN (-3200 1600) $PN 2
R 1
J 2
(-3210 1590);
DISPLAY 0.680851 (-3210 1590);
PAINT MONO (-3210 1590);
FORCEPROP 1 LAST VALUE 0.1UF
J 0
(-3100 1650);
DISPLAY 1.212766 (-3100 1650);
PAINT GREEN (-3100 1650);
FORCEPROP 0 LAST VOLTAGE 25V
J 0
(-3100 1850);
DISPLAY 1.021277 (-3100 1850);
FORCEPROP 0 LAST PACKAGE 0805
J 0
(-3100 1750);
DISPLAY 1.021277 (-3100 1750);
FORCEPROP 1 LAST TOLERANCE 10%
J 0
(-3350 1850);
DISPLAY 1.212766 (-3350 1850);
PAINT GREEN (-3350 1850);
DISPLAY INVISIBLE (-3350 1850);
FORCEPROP 2 LAST CDS_LIB passive
J 0
(-3200 1750);
DISPLAY INVISIBLE (-3200 1750);
FORCEPROP 1 LAST CDS_LMAN_SYM_OUTLINE -50,0,50,-50
J 0
(-3200 1750);
DISPLAY 0.468085 (-3200 1750);
PAINT GREEN (-3200 1750);
DISPLAY INVISIBLE (-3200 1750);
FORCEPROP 1 LAST CLS_PN G105-0B104-EK
J 0
(-3300 1800);
DISPLAY 1.212766 (-3300 1800);
PAINT GREEN (-3300 1800);
DISPLAY INVISIBLE (-3300 1800);
FORCEPROP 1 LAST PATH I149
J 0
(-3300 1800);
DISPLAY 1.212766 (-3300 1800);
PAINT GREEN (-3300 1800);
DISPLAY INVISIBLE (-3300 1800);
FORCEADD VCC..1
(-2400 2300);
FORCEPROP 3 LASTPIN (-2350 2250) SIG_NAME XP2R5V_FPGA\g
J 0
(-2340 2260);
DISPLAY 0.659574 (-2340 2260);
PAINT MONO (-2340 2260);
DISPLAY INVISIBLE (-2340 2260);
FORCEPROP 0 LAST VOLTAGE 2.5V
J 0
(-2500 2450);
DISPLAY 1.021277 (-2500 2450);
DISPLAY BOTH (-2500 2450);
FORCEPROP 1 LAST HDL_POWER XP2R5V_FPGA
J 1
(-2345 2355);
DISPLAY 1.021277 (-2345 2355);
PAINT GREEN (-2345 2355);
FORCEPROP 2 LAST CDS_LIB cls
J 0
(-2400 2300);
DISPLAY INVISIBLE (-2400 2300);
FORCEPROP 1 LAST CDS_LMAN_SYM_OUTLINE -250,250,250,-250
J 0
(-2400 2300);
DISPLAY 0.468085 (-2400 2300);
PAINT GREEN (-2400 2300);
DISPLAY INVISIBLE (-2400 2300);
FORCEPROP 1 LAST BODY_TYPE PLUMBING
J 0
(-2445 2257);
DISPLAY 0.340426 (-2445 2257);
PAINT GREEN (-2445 2257);
DISPLAY INVISIBLE (-2445 2257);
FORCEPROP 1 LAST PATH I150
J 0
(-2365 2390);
DISPLAY 0.808511 (-2365 2390);
PAINT GREEN (-2365 2390);
DISPLAY INVISIBLE (-2365 2390);
FORCEADD ISL80101IRAJZ_DFN10..1
(-7950 1750);
FORCEPROP 1 LAST $LOCATION U25
J 0
(-7900 1850);
DISPLAY 1.212766 (-7900 1850);
PAINT GREEN (-7900 1850);
FORCEPROP 0 LAST CDS_LOCATION U25
J 0
(-7900 1950);
DISPLAY 1.021277 (-7900 1950);
DISPLAY INVISIBLE (-7900 1950);
FORCEPROP 0 LAST $SEC 1
J 0
(-7900 1950);
DISPLAY 0.680851 (-7900 1950);
PAINT MONO (-7900 1950);
DISPLAY INVISIBLE (-7900 1950);
FORCEPROP 0 LAST CDS_SEC 1
J 0
(-7900 1950);
DISPLAY 1.021277 (-7900 1950);
DISPLAY INVISIBLE (-7900 1950);
FORCEPROP 0 LASTPIN (-8050 1150) $PN 7
J 2
(-8060 1160);
DISPLAY 0.680851 (-8060 1160);
PAINT MONO (-8060 1160);
FORCEPROP 0 LASTPIN (-6950 950) $PN 5
J 0
(-6940 960);
DISPLAY 0.680851 (-6940 960);
PAINT MONO (-6940 960);
FORCEPROP 0 LASTPIN (-8050 1350) $PN 8
J 2
(-8060 1360);
DISPLAY 0.680851 (-8060 1360);
PAINT MONO (-8060 1360);
FORCEPROP 0 LASTPIN (-6950 1150) $PN 4
J 0
(-6940 1160);
DISPLAY 0.680851 (-6940 1160);
PAINT MONO (-6940 1160);
FORCEPROP 0 LASTPIN (-6950 1350) $PN 3
J 0
(-6940 1360);
DISPLAY 0.680851 (-6940 1360);
PAINT MONO (-6940 1360);
FORCEPROP 0 LASTPIN (-8050 950) $PN 6
J 2
(-8060 960);
DISPLAY 0.680851 (-8060 960);
PAINT MONO (-8060 960);
FORCEPROP 0 LASTPIN (-6950 850) $PN 11
J 0
(-6940 860);
DISPLAY 0.680851 (-6940 860);
PAINT MONO (-6940 860);
FORCEPROP 0 LASTPIN (-8050 1650) $PN 9
J 2
(-8060 1660);
DISPLAY 0.680851 (-8060 1660);
PAINT MONO (-8060 1660);
FORCEPROP 0 LASTPIN (-8050 1550) $PN 10
J 2
(-8060 1560);
DISPLAY 0.680851 (-8060 1560);
PAINT MONO (-8060 1560);
FORCEPROP 0 LASTPIN (-6950 1650) $PN 1
J 0
(-6940 1660);
DISPLAY 0.680851 (-6940 1660);
PAINT MONO (-6940 1660);
FORCEPROP 0 LASTPIN (-6950 1550) $PN 2
J 0
(-6940 1560);
DISPLAY 0.680851 (-6940 1560);
PAINT MONO (-6940 1560);
FORCEPROP 1 LAST CLS_PN G222-10136-01
J 0
(-7950 1800);
DISPLAY 0.978723 (-7950 1800);
PAINT GREEN (-7950 1800);
FORCEPROP 0 LAST PART_NUMBER ISL80101IRAJZ-T
J 0
(-7900 2000);
DISPLAY 1.021277 (-7900 2000);
FORCEPROP 2 LASTPIN (-6950 1350) SIG_NAME UN$515$ISL80101IRAJZDFN10$I151$SENSE
J 0
(-6940 1360);
DISPLAY 0.659574 (-6940 1360);
PAINT MONO (-6940 1360);
DISPLAY INVISIBLE (-6940 1360);
FORCEPROP 2 LAST CDS_LIB analog
J 0
(-7950 1750);
DISPLAY INVISIBLE (-7950 1750);
FORCEPROP 1 LAST CDS_LMAN_SYM_OUTLINE 0,0,900,-1000
J 0
(-7950 1750);
DISPLAY 0.468085 (-7950 1750);
PAINT GREEN (-7950 1750);
DISPLAY INVISIBLE (-7950 1750);
FORCEPROP 1 LAST PATH I151
J 0
(-7900 1800);
DISPLAY 1.212766 (-7900 1800);
PAINT GREEN (-7900 1800);
DISPLAY INVISIBLE (-7900 1800);
FORCEADD RESISTOR..1
(-10900 1150);
FORCEPROP 1 LAST $LOCATION R225
J 2
(-11001 1205);
DISPLAY 1.212766 (-11001 1205);
PAINT GREEN (-11001 1205);
FORCEPROP 0 LAST CDS_LOCATION R225
J 0
(-10750 1300);
DISPLAY 1.021277 (-10750 1300);
DISPLAY INVISIBLE (-10750 1300);
FORCEPROP 0 LAST $SEC 1
J 0
(-10750 1300);
DISPLAY 0.680851 (-10750 1300);
PAINT MONO (-10750 1300);
DISPLAY INVISIBLE (-10750 1300);
FORCEPROP 0 LAST CDS_SEC 1
J 0
(-10750 1300);
DISPLAY 1.021277 (-10750 1300);
DISPLAY INVISIBLE (-10750 1300);
FORCEPROP 0 LASTPIN (-11000 1150) $PN 1
J 2
(-11010 1160);
DISPLAY 0.680851 (-11010 1160);
PAINT MONO (-11010 1160);
FORCEPROP 0 LASTPIN (-10750 1150) $PN 2
J 0
(-10740 1160);
DISPLAY 0.680851 (-10740 1160);
PAINT MONO (-10740 1160);
FORCEPROP 0 LAST PACKAGE 0402
J 0
(-10950 1050);
DISPLAY 1.021277 (-10950 1050);
FORCEPROP 1 LAST VALUE 330OHM
J 0
(-10750 1200);
DISPLAY 1.212766 (-10750 1200);
PAINT GREEN (-10750 1200);
FORCEPROP 2 LAST CDS_LIB passive
J 0
(-10900 1150);
DISPLAY INVISIBLE (-10900 1150);
FORCEPROP 1 LAST CDS_LMAN_SYM_OUTLINE -50,50,100,-50
J 0
(-10900 1150);
DISPLAY 0.468085 (-10900 1150);
PAINT GREEN (-10900 1150);
DISPLAY INVISIBLE (-10900 1150);
FORCEPROP 1 LAST CLS_PN G155-13300-01
J 0
(-11036 1350);
DISPLAY 1.212766 (-11036 1350);
PAINT GREEN (-11036 1350);
DISPLAY INVISIBLE (-11036 1350);
FORCEPROP 1 LAST TOLERANCE 1%
J 0
(-11097 1405);
DISPLAY 1.212766 (-11097 1405);
PAINT GREEN (-11097 1405);
DISPLAY INVISIBLE (-11097 1405);
FORCEPROP 1 LAST PATH I152
J 0
(-11097 1255);
DISPLAY 1.212766 (-11097 1255);
PAINT GREEN (-11097 1255);
DISPLAY INVISIBLE (-11097 1255);
FORCEADD GND_SG..1
(-10800 1500);
FORCEPROP 3 LASTPIN (-10750 1550) SIG_NAME SG\g
J 0
(-10740 1560);
DISPLAY 0.659574 (-10740 1560);
PAINT MONO (-10740 1560);
DISPLAY INVISIBLE (-10740 1560);
FORCEPROP 1 LAST HDL_POWER SG
J 1
(-10745 1405);
DISPLAY 0.808511 (-10745 1405);
PAINT GREEN (-10745 1405);
FORCEPROP 2 LAST CDS_LIB cls
J 0
(-10800 1500);
DISPLAY INVISIBLE (-10800 1500);
FORCEPROP 1 LAST CDS_LMAN_SYM_OUTLINE 0,0,100,-50
J 0
(-10800 1500);
DISPLAY 0.468085 (-10800 1500);
PAINT GREEN (-10800 1500);
DISPLAY INVISIBLE (-10800 1500);
FORCEPROP 1 LAST BODY_TYPE PLUMBING
J 0
(-10785 1485);
DISPLAY 0.808511 (-10785 1485);
PAINT GREEN (-10785 1485);
DISPLAY INVISIBLE (-10785 1485);
FORCEPROP 1 LAST PATH I153
J 0
(-10765 1500);
DISPLAY 0.808511 (-10765 1500);
PAINT GREEN (-10765 1500);
DISPLAY INVISIBLE (-10765 1500);
FORCEADD CAPACITOR..2
(-11200 1850);
FORCEPROP 1 LAST $LOCATION C224
J 0
(-11150 1700);
DISPLAY 1.212766 (-11150 1700);
PAINT GREEN (-11150 1700);
FORCEPROP 0 LAST CDS_LOCATION C224
J 0
(-11100 1900);
DISPLAY 1.021277 (-11100 1900);
DISPLAY INVISIBLE (-11100 1900);
FORCEPROP 0 LAST $SEC 1
J 0
(-11100 1900);
DISPLAY 0.680851 (-11100 1900);
PAINT MONO (-11100 1900);
DISPLAY INVISIBLE (-11100 1900);
FORCEPROP 0 LAST CDS_SEC 1
J 0
(-11100 1900);
DISPLAY 1.021277 (-11100 1900);
DISPLAY INVISIBLE (-11100 1900);
FORCEPROP 0 LASTPIN (-11200 1950) $PN 1
R 1
J 0
(-11210 1960);
DISPLAY 0.680851 (-11210 1960);
PAINT MONO (-11210 1960);
FORCEPROP 0 LASTPIN (-11200 1700) $PN 2
R 1
J 2
(-11210 1690);
DISPLAY 0.680851 (-11210 1690);
PAINT MONO (-11210 1690);
FORCEPROP 0 LAST PACKAGE 0805
J 0
(-11100 1950);
DISPLAY 1.021277 (-11100 1950);
FORCEPROP 1 LAST VALUE 22UF
J 0
(-11100 1800);
DISPLAY 1.212766 (-11100 1800);
PAINT GREEN (-11100 1800);
FORCEPROP 0 LAST VOLTAGE 10V
J 0
(-11100 2050);
DISPLAY 1.021277 (-11100 2050);
FORCEPROP 1 LAST TOLERANCE 20%
J 0
(-11350 1950);
DISPLAY 1.212766 (-11350 1950);
PAINT GREEN (-11350 1950);
DISPLAY INVISIBLE (-11350 1950);
FORCEPROP 1 LAST CLS_PN G107-0F226-CM
J 0
(-11300 1900);
DISPLAY 1.212766 (-11300 1900);
PAINT GREEN (-11300 1900);
DISPLAY INVISIBLE (-11300 1900);
FORCEPROP 1 LAST CDS_LMAN_SYM_OUTLINE -50,0,50,-50
J 0
(-11200 1850);
DISPLAY 0.468085 (-11200 1850);
PAINT GREEN (-11200 1850);
DISPLAY INVISIBLE (-11200 1850);
FORCEPROP 2 LAST CDS_LIB passive
J 0
(-11200 1850);
DISPLAY INVISIBLE (-11200 1850);
FORCEPROP 1 LAST PATH I154
J 0
(-11300 1900);
DISPLAY 1.212766 (-11300 1900);
PAINT GREEN (-11300 1900);
DISPLAY INVISIBLE (-11300 1900);
FORCEADD CAPACITOR..2
(-10750 1850);
FORCEPROP 1 LAST $LOCATION C226
J 0
(-10650 1750);
DISPLAY 1.212766 (-10650 1750);
PAINT GREEN (-10650 1750);
FORCEPROP 0 LAST CDS_LOCATION C226
J 0
(-10700 2000);
DISPLAY 1.021277 (-10700 2000);
DISPLAY INVISIBLE (-10700 2000);
FORCEPROP 0 LAST $SEC 1
J 0
(-10700 2000);
DISPLAY 0.680851 (-10700 2000);
PAINT MONO (-10700 2000);
DISPLAY INVISIBLE (-10700 2000);
FORCEPROP 0 LAST CDS_SEC 1
J 0
(-10700 2000);
DISPLAY 1.021277 (-10700 2000);
DISPLAY INVISIBLE (-10700 2000);
FORCEPROP 0 LASTPIN (-10750 1950) $PN 1
R 1
J 0
(-10760 1960);
DISPLAY 0.680851 (-10760 1960);
PAINT MONO (-10760 1960);
FORCEPROP 0 LASTPIN (-10750 1700) $PN 2
R 1
J 2
(-10760 1690);
DISPLAY 0.680851 (-10760 1690);
PAINT MONO (-10760 1690);
FORCEPROP 0 LAST VOLTAGE 25V
J 0
(-10650 2050);
FORCEPROP 0 LAST PACKAGE 0402
J 0
(-10650 1950);
FORCEPROP 1 LAST VALUE 0.1UF
J 0
(-10650 1850);
DISPLAY 1.212766 (-10650 1850);
PAINT GREEN (-10650 1850);
FORCEPROP 1 LAST TOLERANCE 10%
J 0
(-10900 1950);
DISPLAY 1.212766 (-10900 1950);
PAINT GREEN (-10900 1950);
DISPLAY INVISIBLE (-10900 1950);
FORCEPROP 1 LAST CLS_PN G105-0B104-EK
J 0
(-10850 1900);
DISPLAY 1.212766 (-10850 1900);
PAINT GREEN (-10850 1900);
DISPLAY INVISIBLE (-10850 1900);
FORCEPROP 0 LAST MATERIAL X7R
J 0
(-10650 2100);
DISPLAY INVISIBLE (-10650 2100);
FORCEPROP 1 LAST CDS_LMAN_SYM_OUTLINE -50,0,50,-50
J 0
(-10750 1850);
DISPLAY 0.468085 (-10750 1850);
PAINT GREEN (-10750 1850);
DISPLAY INVISIBLE (-10750 1850);
FORCEPROP 2 LAST CDS_LIB passive
J 0
(-10750 1850);
DISPLAY INVISIBLE (-10750 1850);
FORCEPROP 1 LAST PATH I155
J 0
(-10850 1900);
DISPLAY 1.212766 (-10850 1900);
PAINT GREEN (-10850 1900);
DISPLAY INVISIBLE (-10850 1900);
FORCEADD VCC..1
(-6150 7400);
FORCEPROP 3 LASTPIN (-6100 7350) SIG_NAME XP3R3V_FPGA\g
J 0
(-6090 7360);
DISPLAY 0.659574 (-6090 7360);
PAINT MONO (-6090 7360);
DISPLAY INVISIBLE (-6090 7360);
FORCEPROP 0 LAST VOLTAGE 3.3V
J 0
(-6400 7550);
DISPLAY 1.021277 (-6400 7550);
DISPLAY BOTH (-6400 7550);
FORCEPROP 1 LAST HDL_POWER XP3R3V_FPGA
J 1
(-6095 7455);
DISPLAY 1.021277 (-6095 7455);
PAINT GREEN (-6095 7455);
FORCEPROP 1 LAST CDS_LMAN_SYM_OUTLINE -250,250,250,-250
J 0
(-6150 7400);
DISPLAY 0.468085 (-6150 7400);
PAINT GREEN (-6150 7400);
DISPLAY INVISIBLE (-6150 7400);
FORCEPROP 2 LAST CDS_LIB cls
J 0
(-6150 7400);
DISPLAY INVISIBLE (-6150 7400);
FORCEPROP 1 LAST BODY_TYPE PLUMBING
J 0
(-6195 7357);
DISPLAY 0.340426 (-6195 7357);
PAINT GREEN (-6195 7357);
DISPLAY INVISIBLE (-6195 7357);
FORCEPROP 1 LAST PATH I163
J 0
(-6115 7490);
DISPLAY 0.808511 (-6115 7490);
PAINT GREEN (-6115 7490);
DISPLAY INVISIBLE (-6115 7490);
FORCEADD VCC..1
(-5800 800);
FORCEPROP 3 LASTPIN (-5750 750) SIG_NAME XP3R3V_FPGA\g
J 0
(-5740 760);
DISPLAY 0.659574 (-5740 760);
PAINT MONO (-5740 760);
DISPLAY INVISIBLE (-5740 760);
FORCEPROP 0 LAST VOLTAGE 3.3V
J 0
(-6050 950);
DISPLAY 1.021277 (-6050 950);
DISPLAY BOTH (-6050 950);
FORCEPROP 1 LAST HDL_POWER XP3R3V_FPGA
J 1
(-5745 855);
DISPLAY 1.021277 (-5745 855);
PAINT GREEN (-5745 855);
FORCEPROP 2 LAST CDS_LIB cls
J 0
(-5800 800);
DISPLAY INVISIBLE (-5800 800);
FORCEPROP 1 LAST CDS_LMAN_SYM_OUTLINE -250,250,250,-250
J 0
(-5800 800);
DISPLAY 0.468085 (-5800 800);
PAINT GREEN (-5800 800);
DISPLAY INVISIBLE (-5800 800);
FORCEPROP 1 LAST BODY_TYPE PLUMBING
J 0
(-5845 757);
DISPLAY 0.340426 (-5845 757);
PAINT GREEN (-5845 757);
DISPLAY INVISIBLE (-5845 757);
FORCEPROP 1 LAST PATH I164
J 0
(-5765 890);
DISPLAY 0.808511 (-5765 890);
PAINT GREEN (-5765 890);
DISPLAY INVISIBLE (-5765 890);
FORCEADD OFFPAGE_OUT..1
R 2
(-7950 6400);
FORCEPROP 2 LAST $XR0 24F15> 
J 0
(-8164 6400);
DISPLAY 0.638298 (-8164 6400);
PAINT MONO (-8164 6400);
FORCEPROP 2 LAST $XR1 25C9<> 
J 0
(-8374 6400);
DISPLAY 0.638298 (-8374 6400);
PAINT MONO (-8374 6400);
FORCEPROP 2 LAST $XR3 32H7> 
J 0
(-8764 6400);
DISPLAY 0.638298 (-8764 6400);
PAINT MONO (-8764 6400);
FORCEPROP 2 LAST $XR2 31K11> 
J 0
(-8554 6400);
DISPLAY 0.638298 (-8554 6400);
PAINT MONO (-8554 6400);
FORCEPROP 2 LAST $XR4 10F12< 
J 0
(-8764 6400);
DISPLAY 0.638298 (-8764 6400);
PAINT MONO (-8764 6400);
FORCEPROP 1 LAST BODY_TYPE COMMENT
J 2
(-7960 6535);
DISPLAY 0.808511 (-7960 6535);
PAINT GREEN (-7960 6535);
DISPLAY INVISIBLE (-7960 6535);
FORCEPROP 1 LAST CDS_LMAN_SYM_OUTLINE -50,50,50,-50
J 2
(-7950 6400);
DISPLAY 0.468085 (-7950 6400);
PAINT GREEN (-7950 6400);
DISPLAY INVISIBLE (-7950 6400);
FORCEPROP 2 LAST CDS_LIB cls
J 0
(-7950 6400);
DISPLAY INVISIBLE (-7950 6400);
FORCEPROP 1 LAST OFFPAGE TRUE
J 2
(-7960 6455);
DISPLAY 0.808511 (-7960 6455);
PAINT GREEN (-7960 6455);
DISPLAY INVISIBLE (-7960 6455);
FORCEPROP 2 LAST PATH I166
J 0
(-7900 6500);
DISPLAY 1.021277 (-7900 6500);
DISPLAY INVISIBLE (-7900 6500);
FORCEADD RESISTOR..1
(-6650 6400);
FORCEPROP 1 LAST $LOCATION R143
J 2
(-6850 6400);
DISPLAY 1.212766 (-6850 6400);
PAINT GREEN (-6850 6400);
FORCEPROP 0 LAST CDS_LOCATION R143
J 0
(-6450 6500);
DISPLAY 1.021277 (-6450 6500);
DISPLAY INVISIBLE (-6450 6500);
FORCEPROP 0 LAST $SEC 1
J 0
(-6450 6500);
DISPLAY 0.680851 (-6450 6500);
PAINT MONO (-6450 6500);
DISPLAY INVISIBLE (-6450 6500);
FORCEPROP 0 LAST CDS_SEC 1
J 0
(-6450 6500);
DISPLAY 1.021277 (-6450 6500);
DISPLAY INVISIBLE (-6450 6500);
FORCEPROP 0 LASTPIN (-6750 6400) $PN 1
J 2
(-6760 6410);
DISPLAY 0.680851 (-6760 6410);
PAINT MONO (-6760 6410);
FORCEPROP 0 LASTPIN (-6500 6400) $PN 2
J 0
(-6490 6410);
DISPLAY 0.680851 (-6490 6410);
PAINT MONO (-6490 6410);
FORCEPROP 0 LAST PACKAGE 0402
J 0
(-6450 6550);
DISPLAY 1.021277 (-6450 6550);
FORCEPROP 1 LAST VALUE 33OHM
J 0
(-6450 6400);
DISPLAY 1.234043 (-6450 6400);
PAINT GREEN (-6450 6400);
FORCEPROP 2 LAST SIGNAL_MODEL DEFAULT_RESISTOR_33OHM_2_1
J 0
(-6800 6600);
DISPLAY 1.021277 (-6800 6600);
DISPLAY INVISIBLE (-6800 6600);
FORCEPROP 1 LAST CDS_LMAN_SYM_OUTLINE -50,50,100,-50
J 0
(-6650 6400);
DISPLAY 0.468085 (-6650 6400);
PAINT GREEN (-6650 6400);
DISPLAY INVISIBLE (-6650 6400);
FORCEPROP 2 LAST CDS_LIB passive
J 0
(-6650 6400);
DISPLAY INVISIBLE (-6650 6400);
FORCEPROP 1 LAST CLS_PN G155-133R0-01
J 0
(-6786 6600);
DISPLAY 1.212766 (-6786 6600);
PAINT GREEN (-6786 6600);
DISPLAY INVISIBLE (-6786 6600);
FORCEPROP 1 LAST TOLERANCE 1%
J 0
(-6847 6655);
DISPLAY 1.212766 (-6847 6655);
PAINT GREEN (-6847 6655);
DISPLAY INVISIBLE (-6847 6655);
FORCEPROP 1 LAST PATH I167
J 0
(-6847 6505);
DISPLAY 1.212766 (-6847 6505);
PAINT GREEN (-6847 6505);
DISPLAY INVISIBLE (-6847 6505);
FORCEADD CAPACITOR..2
(-10150 800);
FORCEPROP 1 LAST $LOCATION C293
J 0
(-10550 650);
DISPLAY 1.212766 (-10550 650);
PAINT GREEN (-10550 650);
FORCEPROP 0 LAST CDS_LOCATION C293
J 0
(-10500 1000);
DISPLAY 1.021277 (-10500 1000);
DISPLAY INVISIBLE (-10500 1000);
FORCEPROP 0 LAST $SEC 1
J 0
(-10500 1000);
DISPLAY 0.680851 (-10500 1000);
PAINT MONO (-10500 1000);
DISPLAY INVISIBLE (-10500 1000);
FORCEPROP 0 LAST CDS_SEC 1
J 0
(-10500 1000);
DISPLAY 1.021277 (-10500 1000);
DISPLAY INVISIBLE (-10500 1000);
FORCEPROP 0 LASTPIN (-10150 900) $PN 1
R 1
J 0
(-10160 910);
DISPLAY 0.680851 (-10160 910);
PAINT MONO (-10160 910);
FORCEPROP 0 LASTPIN (-10150 650) $PN 2
R 1
J 2
(-10160 640);
DISPLAY 0.680851 (-10160 640);
PAINT MONO (-10160 640);
FORCEPROP 1 LAST VALUE 0.22UF
J 0
(-10550 850);
DISPLAY 1.212766 (-10550 850);
PAINT GREEN (-10550 850);
FORCEPROP 0 LAST VOLTAGE 25V
J 0
(-10550 950);
DISPLAY 1.021277 (-10550 950);
FORCEPROP 0 LAST PACKAGE 0402
J 0
(-10550 750);
DISPLAY 1.021277 (-10550 750);
FORCEPROP 2 LAST CDS_LIB passive
J 0
(-10150 800);
DISPLAY INVISIBLE (-10150 800);
FORCEPROP 1 LAST CDS_LMAN_SYM_OUTLINE -50,0,50,-50
J 0
(-10150 800);
DISPLAY 0.468085 (-10150 800);
PAINT GREEN (-10150 800);
DISPLAY INVISIBLE (-10150 800);
FORCEPROP 1 LAST TOLERANCE 10%
J 0
(-10300 900);
DISPLAY 1.212766 (-10300 900);
PAINT GREEN (-10300 900);
DISPLAY INVISIBLE (-10300 900);
FORCEPROP 1 LAST CLS_PN G105-0B224-DK
J 0
(-10250 850);
DISPLAY 1.212766 (-10250 850);
PAINT GREEN (-10250 850);
DISPLAY INVISIBLE (-10250 850);
FORCEPROP 1 LAST PATH I168
J 0
(-10250 850);
DISPLAY 1.212766 (-10250 850);
PAINT GREEN (-10250 850);
DISPLAY INVISIBLE (-10250 850);
FORCEADD CAPACITOR..2
(-10100 6300);
FORCEPROP 1 LAST $LOCATION C294
J 0
(-10500 6100);
DISPLAY 1.212766 (-10500 6100);
PAINT GREEN (-10500 6100);
FORCEPROP 0 LAST CDS_LOCATION C294
J 0
(-10450 6500);
DISPLAY 1.021277 (-10450 6500);
DISPLAY INVISIBLE (-10450 6500);
FORCEPROP 0 LAST $SEC 1
J 0
(-10450 6500);
DISPLAY 0.680851 (-10450 6500);
PAINT MONO (-10450 6500);
DISPLAY INVISIBLE (-10450 6500);
FORCEPROP 0 LAST CDS_SEC 1
J 0
(-10450 6500);
DISPLAY 1.021277 (-10450 6500);
DISPLAY INVISIBLE (-10450 6500);
FORCEPROP 0 LASTPIN (-10100 6400) $PN 1
R 1
J 0
(-10110 6410);
DISPLAY 0.680851 (-10110 6410);
PAINT MONO (-10110 6410);
FORCEPROP 0 LASTPIN (-10100 6150) $PN 2
R 1
J 2
(-10110 6140);
DISPLAY 0.680851 (-10110 6140);
PAINT MONO (-10110 6140);
FORCEPROP 0 LAST VOLTAGE 25V
J 0
(-10500 6400);
DISPLAY 1.021277 (-10500 6400);
FORCEPROP 1 LAST VALUE 0.22UF
J 0
(-10500 6300);
DISPLAY 1.212766 (-10500 6300);
PAINT GREEN (-10500 6300);
FORCEPROP 0 LAST PACKAGE 0402
J 0
(-10500 6200);
DISPLAY 1.021277 (-10500 6200);
FORCEPROP 1 LAST PATH I169
J 0
(-10200 6350);
DISPLAY 1.212766 (-10200 6350);
PAINT GREEN (-10200 6350);
DISPLAY INVISIBLE (-10200 6350);
FORCEPROP 1 LAST CLS_PN G105-0B224-DK
J 0
(-10200 6350);
DISPLAY 1.212766 (-10200 6350);
PAINT GREEN (-10200 6350);
DISPLAY INVISIBLE (-10200 6350);
FORCEPROP 1 LAST TOLERANCE 10%
J 0
(-10250 6400);
DISPLAY 1.212766 (-10250 6400);
PAINT GREEN (-10250 6400);
DISPLAY INVISIBLE (-10250 6400);
FORCEPROP 2 LAST CDS_LIB passive
J 0
(-10100 6300);
DISPLAY INVISIBLE (-10100 6300);
FORCEPROP 1 LAST CDS_LMAN_SYM_OUTLINE -50,0,50,-50
J 0
(-10100 6300);
DISPLAY 0.468085 (-10100 6300);
PAINT GREEN (-10100 6300);
DISPLAY INVISIBLE (-10100 6300);
FORCEADD GND_SG..1
(-10150 5700);
FORCEPROP 3 LASTPIN (-10100 5750) SIG_NAME SG\g
J 0
(-10090 5760);
DISPLAY 0.659574 (-10090 5760);
PAINT MONO (-10090 5760);
DISPLAY INVISIBLE (-10090 5760);
FORCEPROP 1 LAST HDL_POWER SG
J 1
(-10095 5605);
DISPLAY 0.808511 (-10095 5605);
PAINT GREEN (-10095 5605);
FORCEPROP 1 LAST PATH I55
J 0
(-10115 5700);
DISPLAY 0.808511 (-10115 5700);
PAINT GREEN (-10115 5700);
DISPLAY INVISIBLE (-10115 5700);
FORCEPROP 1 LAST BODY_TYPE PLUMBING
J 0
(-10135 5685);
DISPLAY 0.808511 (-10135 5685);
PAINT GREEN (-10135 5685);
DISPLAY INVISIBLE (-10135 5685);
FORCEPROP 1 LAST CDS_LMAN_SYM_OUTLINE 0,0,100,-50
J 0
(-10150 5700);
DISPLAY 0.468085 (-10150 5700);
PAINT GREEN (-10150 5700);
DISPLAY INVISIBLE (-10150 5700);
FORCEPROP 2 LAST CDS_LIB cls
J 0
(-10150 5700);
DISPLAY INVISIBLE (-10150 5700);
FORCEADD RESISTOR..2
(-9650 6250);
FORCEPROP 1 LAST $LOCATION R237
J 0
(-9600 6100);
DISPLAY 1.212766 (-9600 6100);
PAINT GREEN (-9600 6100);
FORCEPROP 0 LAST CDS_LOCATION R237
J 0
(-10100 6300);
DISPLAY 1.021277 (-10100 6300);
DISPLAY INVISIBLE (-10100 6300);
FORCEPROP 0 LAST $SEC 1
J 0
(-10100 6300);
DISPLAY 0.680851 (-10100 6300);
PAINT MONO (-10100 6300);
DISPLAY INVISIBLE (-10100 6300);
FORCEPROP 0 LAST CDS_SEC 1
J 0
(-10100 6300);
DISPLAY 1.021277 (-10100 6300);
DISPLAY INVISIBLE (-10100 6300);
FORCEPROP 0 LASTPIN (-9650 6350) $PN 1
R 1
J 0
(-9660 6360);
DISPLAY 0.680851 (-9660 6360);
PAINT MONO (-9660 6360);
FORCEPROP 0 LASTPIN (-9650 6100) $PN 2
R 1
J 2
(-9660 6090);
DISPLAY 0.680851 (-9660 6090);
PAINT MONO (-9660 6090);
FORCEPROP 0 LAST NO_ASSY TRUE
J 0
(-9950 6200);
DISPLAY 1.021277 (-9950 6200);
DISPLAY BOTH (-9950 6200);
FORCEPROP 1 LAST VALUE 10KOHM
J 0
(-9600 6250);
DISPLAY 1.212766 (-9600 6250);
PAINT GREEN (-9600 6250);
FORCEPROP 0 LAST PACKAGE 0402
J 0
(-9600 6400);
DISPLAY 1.021277 (-9600 6400);
FORCEPROP 1 LAST CDS_LMAN_SYM_OUTLINE -50,50,50,-100
J 0
(-9650 6250);
DISPLAY 0.468085 (-9650 6250);
PAINT GREEN (-9650 6250);
DISPLAY INVISIBLE (-9650 6250);
FORCEPROP 2 LAST CDS_LIB passive
J 0
(-9650 6250);
DISPLAY INVISIBLE (-9650 6250);
FORCEPROP 1 LAST CLS_PN G155-11002-01
J 0
(-9786 6450);
DISPLAY 1.212766 (-9786 6450);
PAINT GREEN (-9786 6450);
DISPLAY INVISIBLE (-9786 6450);
FORCEPROP 1 LAST TOLERANCE 1%
J 0
(-9847 6505);
DISPLAY 1.212766 (-9847 6505);
PAINT GREEN (-9847 6505);
DISPLAY INVISIBLE (-9847 6505);
FORCEPROP 1 LAST PATH I56
J 0
(-9847 6355);
DISPLAY 1.212766 (-9847 6355);
PAINT GREEN (-9847 6355);
DISPLAY INVISIBLE (-9847 6355);
FORCEADD OFFPAGE_IN..1
(-11900 6600);
FORCEPROP 2 LAST $XR0 25F6<> 
J 0
(-12114 6600);
DISPLAY 0.638298 (-12114 6600);
PAINT MONO (-12114 6600);
FORCEPROP 2 LAST $XR1 30K11> 
J 0
(-12324 6600);
DISPLAY 0.638298 (-12324 6600);
PAINT MONO (-12324 6600);
FORCEPROP 2 LAST $XR2 31J2< 
J 0
(-12504 6600);
DISPLAY 0.638298 (-12504 6600);
PAINT MONO (-12504 6600);
FORCEPROP 2 LAST $XR3 32E2< 
J 0
(-12684 6600);
DISPLAY 0.638298 (-12684 6600);
PAINT MONO (-12684 6600);
FORCEPROP 2 LAST PATH I58
J 0
(-12050 6650);
DISPLAY 1.021277 (-12050 6650);
DISPLAY INVISIBLE (-12050 6650);
FORCEPROP 1 LAST OFFPAGE TRUE
J 0
(-11890 6655);
DISPLAY 0.808511 (-11890 6655);
PAINT GREEN (-11890 6655);
DISPLAY INVISIBLE (-11890 6655);
FORCEPROP 1 LAST BODY_TYPE COMMENT
J 0
(-11890 6735);
DISPLAY 0.808511 (-11890 6735);
PAINT GREEN (-11890 6735);
DISPLAY INVISIBLE (-11890 6735);
FORCEPROP 1 LAST CDS_LMAN_SYM_OUTLINE -50,50,50,-50
J 0
(-11900 6600);
DISPLAY 0.468085 (-11900 6600);
PAINT GREEN (-11900 6600);
DISPLAY INVISIBLE (-11900 6600);
FORCEPROP 2 LAST CDS_LIB cls
J 0
(-11900 6600);
DISPLAY INVISIBLE (-11900 6600);
FORCEADD GND_SG..1
(-7850 4700);
FORCEPROP 3 LASTPIN (-7800 4750) SIG_NAME SG\g
J 0
(-7790 4760);
DISPLAY 0.659574 (-7790 4760);
PAINT MONO (-7790 4760);
DISPLAY INVISIBLE (-7790 4760);
FORCEPROP 1 LAST HDL_POWER SG
J 1
(-7800 4600);
DISPLAY 0.808511 (-7800 4600);
PAINT GREEN (-7800 4600);
FORCEPROP 2 LAST CDS_LIB cls
J 0
(-7850 4700);
DISPLAY INVISIBLE (-7850 4700);
FORCEPROP 1 LAST CDS_LMAN_SYM_OUTLINE 0,0,100,-50
J 0
(-7850 4700);
DISPLAY 0.468085 (-7850 4700);
PAINT GREEN (-7850 4700);
DISPLAY INVISIBLE (-7850 4700);
FORCEPROP 1 LAST BODY_TYPE PLUMBING
J 0
(-7835 4685);
DISPLAY 0.808511 (-7835 4685);
PAINT GREEN (-7835 4685);
DISPLAY INVISIBLE (-7835 4685);
FORCEPROP 1 LAST PATH I60
J 0
(-7815 4700);
DISPLAY 0.808511 (-7815 4700);
PAINT GREEN (-7815 4700);
DISPLAY INVISIBLE (-7815 4700);
FORCEADD CAPACITOR..2
(-7800 5400);
FORCEPROP 1 LAST $LOCATION C232
J 0
(-7700 5450);
DISPLAY 1.212766 (-7700 5450);
PAINT GREEN (-7700 5450);
FORCEPROP 0 LAST CDS_LOCATION C232
J 0
(-7700 5650);
DISPLAY 1.021277 (-7700 5650);
DISPLAY INVISIBLE (-7700 5650);
FORCEPROP 0 LAST $SEC 1
J 0
(-7700 5650);
DISPLAY 0.680851 (-7700 5650);
PAINT MONO (-7700 5650);
DISPLAY INVISIBLE (-7700 5650);
FORCEPROP 0 LAST CDS_SEC 1
J 0
(-7700 5650);
DISPLAY 1.021277 (-7700 5650);
DISPLAY INVISIBLE (-7700 5650);
FORCEPROP 0 LASTPIN (-7800 5500) $PN 1
R 1
J 0
(-7810 5510);
DISPLAY 0.680851 (-7810 5510);
PAINT MONO (-7810 5510);
FORCEPROP 0 LASTPIN (-7800 5250) $PN 2
R 1
J 2
(-7810 5240);
DISPLAY 0.680851 (-7810 5240);
PAINT MONO (-7810 5240);
FORCEPROP 0 LAST VOLTAGE 10V
J 0
(-7700 5650);
DISPLAY 1.021277 (-7700 5650);
FORCEPROP 0 LAST PACKAGE 0805
J 0
(-7700 5550);
DISPLAY 1.021277 (-7700 5550);
FORCEPROP 1 LAST VALUE 22UF
J 0
(-7700 5350);
DISPLAY 1.212766 (-7700 5350);
PAINT GREEN (-7700 5350);
FORCEPROP 1 LAST TOLERANCE 20%
J 0
(-7950 5500);
DISPLAY 1.212766 (-7950 5500);
PAINT GREEN (-7950 5500);
DISPLAY INVISIBLE (-7950 5500);
FORCEPROP 1 LAST CLS_PN G107-0F226-CM
J 0
(-7900 5450);
DISPLAY 1.212766 (-7900 5450);
PAINT GREEN (-7900 5450);
DISPLAY INVISIBLE (-7900 5450);
FORCEPROP 1 LAST CDS_LMAN_SYM_OUTLINE -50,0,50,-50
J 0
(-7800 5400);
DISPLAY 0.468085 (-7800 5400);
PAINT GREEN (-7800 5400);
DISPLAY INVISIBLE (-7800 5400);
FORCEPROP 2 LAST CDS_LIB passive
J 0
(-7800 5400);
DISPLAY INVISIBLE (-7800 5400);
FORCEPROP 1 LAST PATH I61
J 0
(-7900 5450);
DISPLAY 1.212766 (-7900 5450);
PAINT GREEN (-7900 5450);
DISPLAY INVISIBLE (-7900 5450);
FORCEADD CAPACITOR..2
(-7250 5450);
FORCEPROP 1 LAST $LOCATION C233
J 0
(-7100 5450);
DISPLAY 1.212766 (-7100 5450);
PAINT GREEN (-7100 5450);
FORCEPROP 0 LAST CDS_LOCATION C233
J 0
(-7150 5700);
DISPLAY 1.021277 (-7150 5700);
DISPLAY INVISIBLE (-7150 5700);
FORCEPROP 0 LAST $SEC 1
J 0
(-7150 5700);
DISPLAY 0.680851 (-7150 5700);
PAINT MONO (-7150 5700);
DISPLAY INVISIBLE (-7150 5700);
FORCEPROP 0 LAST CDS_SEC 1
J 0
(-7150 5700);
DISPLAY 1.021277 (-7150 5700);
DISPLAY INVISIBLE (-7150 5700);
FORCEPROP 0 LASTPIN (-7250 5550) $PN 1
R 1
J 0
(-7260 5560);
DISPLAY 0.680851 (-7260 5560);
PAINT MONO (-7260 5560);
FORCEPROP 0 LASTPIN (-7250 5300) $PN 2
R 1
J 2
(-7260 5290);
DISPLAY 0.680851 (-7260 5290);
PAINT MONO (-7260 5290);
FORCEPROP 0 LAST VOLTAGE 10V
J 0
(-7100 5650);
DISPLAY 1.021277 (-7100 5650);
FORCEPROP 0 LAST PACKAGE 0402
J 0
(-7100 5550);
DISPLAY 1.021277 (-7100 5550);
FORCEPROP 1 LAST VALUE 0.1UF
J 0
(-7100 5350);
DISPLAY 1.212766 (-7100 5350);
PAINT GREEN (-7100 5350);
FORCEPROP 1 LAST TOLERANCE 10%
J 0
(-7400 5550);
DISPLAY 1.212766 (-7400 5550);
PAINT GREEN (-7400 5550);
DISPLAY INVISIBLE (-7400 5550);
FORCEPROP 2 LAST CDS_LIB passive
J 0
(-7250 5450);
DISPLAY INVISIBLE (-7250 5450);
FORCEPROP 1 LAST CDS_LMAN_SYM_OUTLINE -50,0,50,-50
J 0
(-7250 5450);
DISPLAY 0.468085 (-7250 5450);
PAINT GREEN (-7250 5450);
DISPLAY INVISIBLE (-7250 5450);
FORCEPROP 1 LAST CLS_PN G105-0B104-CK
J 0
(-7350 5500);
DISPLAY 1.212766 (-7350 5500);
PAINT GREEN (-7350 5500);
DISPLAY INVISIBLE (-7350 5500);
FORCEPROP 1 LAST PATH I63
J 0
(-7350 5500);
DISPLAY 1.212766 (-7350 5500);
PAINT GREEN (-7350 5500);
DISPLAY INVISIBLE (-7350 5500);
FORCEADD CAPACITOR..2
(-4150 5400);
FORCEPROP 1 LAST $LOCATION C237
J 0
(-4550 5250);
DISPLAY 1.212766 (-4550 5250);
PAINT GREEN (-4550 5250);
FORCEPROP 0 LAST CDS_LOCATION C237
J 0
(-4050 5650);
DISPLAY 1.021277 (-4050 5650);
DISPLAY INVISIBLE (-4050 5650);
FORCEPROP 0 LAST $SEC 1
J 0
(-4050 5650);
DISPLAY 0.680851 (-4050 5650);
PAINT MONO (-4050 5650);
DISPLAY INVISIBLE (-4050 5650);
FORCEPROP 0 LAST CDS_SEC 1
J 0
(-4050 5650);
DISPLAY 1.021277 (-4050 5650);
DISPLAY INVISIBLE (-4050 5650);
FORCEPROP 0 LASTPIN (-4150 5500) $PN 1
R 1
J 0
(-4160 5510);
DISPLAY 0.680851 (-4160 5510);
PAINT MONO (-4160 5510);
FORCEPROP 0 LASTPIN (-4150 5250) $PN 2
R 1
J 2
(-4160 5240);
DISPLAY 0.680851 (-4160 5240);
PAINT MONO (-4160 5240);
FORCEPROP 0 LAST VOLTAGE 10V
J 0
(-4550 5650);
DISPLAY 1.021277 (-4550 5650);
FORCEPROP 0 LAST PACKAGE 0402
J 0
(-4550 5550);
DISPLAY 1.021277 (-4550 5550);
FORCEPROP 1 LAST VALUE 0.1UF
J 0
(-4550 5400);
DISPLAY 1.212766 (-4550 5400);
PAINT GREEN (-4550 5400);
FORCEPROP 1 LAST CLS_PN G105-0B104-CK
J 0
(-4250 5450);
DISPLAY 1.212766 (-4250 5450);
PAINT GREEN (-4250 5450);
DISPLAY INVISIBLE (-4250 5450);
FORCEPROP 1 LAST CDS_LMAN_SYM_OUTLINE -50,0,50,-50
J 0
(-4150 5400);
DISPLAY 0.468085 (-4150 5400);
PAINT GREEN (-4150 5400);
DISPLAY INVISIBLE (-4150 5400);
FORCEPROP 2 LAST CDS_LIB passive
J 0
(-4150 5400);
DISPLAY INVISIBLE (-4150 5400);
FORCEPROP 1 LAST TOLERANCE 10%
J 0
(-4300 5500);
DISPLAY 1.212766 (-4300 5500);
PAINT GREEN (-4300 5500);
DISPLAY INVISIBLE (-4300 5500);
FORCEPROP 1 LAST PATH I64
J 0
(-4250 5450);
DISPLAY 1.212766 (-4250 5450);
PAINT GREEN (-4250 5450);
DISPLAY INVISIBLE (-4250 5450);
FORCEADD GND_SG..1
(-4450 6100);
FORCEPROP 3 LASTPIN (-4400 6150) SIG_NAME SG\g
J 0
(-4390 6160);
DISPLAY 0.659574 (-4390 6160);
PAINT MONO (-4390 6160);
DISPLAY INVISIBLE (-4390 6160);
FORCEPROP 1 LAST HDL_POWER SG
J 1
(-4395 6005);
DISPLAY 0.808511 (-4395 6005);
PAINT GREEN (-4395 6005);
FORCEPROP 2 LAST CDS_LIB cls
J 0
(-4450 6100);
DISPLAY INVISIBLE (-4450 6100);
FORCEPROP 1 LAST CDS_LMAN_SYM_OUTLINE 0,0,100,-50
J 0
(-4450 6100);
DISPLAY 0.468085 (-4450 6100);
PAINT GREEN (-4450 6100);
DISPLAY INVISIBLE (-4450 6100);
FORCEPROP 1 LAST BODY_TYPE PLUMBING
J 0
(-4435 6085);
DISPLAY 0.808511 (-4435 6085);
PAINT GREEN (-4435 6085);
DISPLAY INVISIBLE (-4435 6085);
FORCEPROP 1 LAST PATH I65
J 0
(-4415 6100);
DISPLAY 0.808511 (-4415 6100);
PAINT GREEN (-4415 6100);
DISPLAY INVISIBLE (-4415 6100);
FORCEADD CAPACITOR..2
(-4400 6400);
FORCEPROP 1 LAST $LOCATION C236
J 0
(-4300 6300);
DISPLAY 1.212766 (-4300 6300);
PAINT GREEN (-4300 6300);
FORCEPROP 0 LAST CDS_LOCATION C236
J 0
(-4300 6650);
DISPLAY 1.021277 (-4300 6650);
DISPLAY INVISIBLE (-4300 6650);
FORCEPROP 0 LAST $SEC 1
J 0
(-4300 6650);
DISPLAY 0.680851 (-4300 6650);
PAINT MONO (-4300 6650);
DISPLAY INVISIBLE (-4300 6650);
FORCEPROP 0 LAST CDS_SEC 1
J 0
(-4300 6650);
DISPLAY 1.021277 (-4300 6650);
DISPLAY INVISIBLE (-4300 6650);
FORCEPROP 0 LASTPIN (-4400 6500) $PN 1
R 1
J 0
(-4410 6510);
DISPLAY 0.680851 (-4410 6510);
PAINT MONO (-4410 6510);
FORCEPROP 0 LASTPIN (-4400 6250) $PN 2
R 1
J 2
(-4410 6240);
DISPLAY 0.680851 (-4410 6240);
PAINT MONO (-4410 6240);
FORCEPROP 1 LAST VALUE 0.1UF
J 0
(-4300 6200);
DISPLAY 1.212766 (-4300 6200);
PAINT GREEN (-4300 6200);
FORCEPROP 0 LAST VOLTAGE 25V
J 0
(-4300 6400);
DISPLAY 1.021277 (-4300 6400);
FORCEPROP 0 LAST PACKAGE 0402
J 0
(-4300 6500);
DISPLAY 1.021277 (-4300 6500);
FORCEPROP 1 LAST TOLERANCE 10%
J 0
(-4550 6500);
DISPLAY 1.212766 (-4550 6500);
PAINT GREEN (-4550 6500);
DISPLAY INVISIBLE (-4550 6500);
FORCEPROP 2 LAST CDS_LIB passive
J 0
(-4400 6400);
DISPLAY INVISIBLE (-4400 6400);
FORCEPROP 1 LAST CDS_LMAN_SYM_OUTLINE -50,0,50,-50
J 0
(-4400 6400);
DISPLAY 0.468085 (-4400 6400);
PAINT GREEN (-4400 6400);
DISPLAY INVISIBLE (-4400 6400);
FORCEPROP 1 LAST CLS_PN G105-0B104-EK
J 0
(-4500 6450);
DISPLAY 1.212766 (-4500 6450);
PAINT GREEN (-4500 6450);
DISPLAY INVISIBLE (-4500 6450);
FORCEPROP 1 LAST PATH I66
J 0
(-4500 6450);
DISPLAY 1.212766 (-4500 6450);
PAINT GREEN (-4500 6450);
DISPLAY INVISIBLE (-4500 6450);
FORCEADD RESISTOR..2
(-8600 7150);
FORCEPROP 1 LAST $LOCATION R260
J 0
(-8550 7000);
DISPLAY 1.212766 (-8550 7000);
PAINT GREEN (-8550 7000);
FORCEPROP 0 LAST CDS_LOCATION R260
J 0
(-8550 7300);
DISPLAY 1.021277 (-8550 7300);
DISPLAY INVISIBLE (-8550 7300);
FORCEPROP 0 LAST $SEC 1
J 0
(-8550 7300);
DISPLAY 0.680851 (-8550 7300);
PAINT MONO (-8550 7300);
DISPLAY INVISIBLE (-8550 7300);
FORCEPROP 0 LAST CDS_SEC 1
J 0
(-8550 7300);
DISPLAY 1.021277 (-8550 7300);
DISPLAY INVISIBLE (-8550 7300);
FORCEPROP 0 LASTPIN (-8600 7250) $PN 1
R 1
J 0
(-8610 7260);
DISPLAY 0.680851 (-8610 7260);
PAINT MONO (-8610 7260);
FORCEPROP 0 LASTPIN (-8600 7000) $PN 2
R 1
J 2
(-8610 6990);
DISPLAY 0.680851 (-8610 6990);
PAINT MONO (-8610 6990);
FORCEPROP 0 LAST PACKAGE 0402
J 0
(-8550 7350);
DISPLAY 1.021277 (-8550 7350);
FORCEPROP 1 LAST VALUE 1KOHM
J 0
(-8550 7200);
DISPLAY 1.212766 (-8550 7200);
PAINT GREEN (-8550 7200);
FORCEPROP 0 LAST NO_ASSY TRUE
J 0
(-8450 7100);
DISPLAY 1.021277 (-8450 7100);
DISPLAY BOTH (-8450 7100);
FORCEPROP 2 LAST CDS_LIB passive
J 0
(-8600 7150);
DISPLAY INVISIBLE (-8600 7150);
FORCEPROP 1 LAST CDS_LMAN_SYM_OUTLINE -50,50,50,-100
J 0
(-8600 7150);
DISPLAY 0.468085 (-8600 7150);
PAINT GREEN (-8600 7150);
DISPLAY INVISIBLE (-8600 7150);
FORCEPROP 1 LAST CLS_PN G155-11001-01
J 0
(-8736 7350);
DISPLAY 1.212766 (-8736 7350);
PAINT GREEN (-8736 7350);
DISPLAY INVISIBLE (-8736 7350);
FORCEPROP 1 LAST TOLERANCE 1%
J 0
(-8797 7405);
DISPLAY 1.212766 (-8797 7405);
PAINT GREEN (-8797 7405);
DISPLAY INVISIBLE (-8797 7405);
FORCEPROP 1 LAST PATH I67
J 0
(-8797 7255);
DISPLAY 1.212766 (-8797 7255);
PAINT GREEN (-8797 7255);
DISPLAY INVISIBLE (-8797 7255);
FORCEADD RESISTOR..2
(-6100 7000);
FORCEPROP 1 LAST $LOCATION R295
J 0
(-6400 6850);
DISPLAY 1.212766 (-6400 6850);
PAINT GREEN (-6400 6850);
FORCEPROP 0 LAST CDS_LOCATION R295
J 0
(-6450 7150);
DISPLAY 1.021277 (-6450 7150);
DISPLAY INVISIBLE (-6450 7150);
FORCEPROP 0 LAST $SEC 1
J 0
(-6450 7150);
DISPLAY 0.680851 (-6450 7150);
PAINT MONO (-6450 7150);
DISPLAY INVISIBLE (-6450 7150);
FORCEPROP 0 LAST CDS_SEC 1
J 0
(-6450 7150);
DISPLAY 1.021277 (-6450 7150);
DISPLAY INVISIBLE (-6450 7150);
FORCEPROP 0 LASTPIN (-6100 7100) $PN 1
R 1
J 0
(-6110 7110);
DISPLAY 0.680851 (-6110 7110);
PAINT MONO (-6110 7110);
FORCEPROP 0 LASTPIN (-6100 6850) $PN 2
R 1
J 2
(-6110 6840);
DISPLAY 0.680851 (-6110 6840);
PAINT MONO (-6110 6840);
FORCEPROP 0 LAST NO_ASSY TRUE
J 0
(-6750 6950);
DISPLAY 1.021277 (-6750 6950);
DISPLAY BOTH (-6750 6950);
FORCEPROP 0 LAST PACKAGE 0402
J 0
(-6450 7200);
DISPLAY 1.021277 (-6450 7200);
FORCEPROP 1 LAST VALUE 10KOHM
J 0
(-6450 7050);
DISPLAY 1.212766 (-6450 7050);
PAINT GREEN (-6450 7050);
FORCEPROP 1 LAST CDS_LMAN_SYM_OUTLINE -50,50,50,-100
J 0
(-6100 7000);
DISPLAY 0.468085 (-6100 7000);
PAINT GREEN (-6100 7000);
DISPLAY INVISIBLE (-6100 7000);
FORCEPROP 2 LAST CDS_LIB passive
J 0
(-6100 7000);
DISPLAY INVISIBLE (-6100 7000);
FORCEPROP 1 LAST CLS_PN G155-11002-01
J 0
(-6236 7200);
DISPLAY 1.212766 (-6236 7200);
PAINT GREEN (-6236 7200);
DISPLAY INVISIBLE (-6236 7200);
FORCEPROP 1 LAST TOLERANCE 1%
J 0
(-6297 7255);
DISPLAY 1.212766 (-6297 7255);
PAINT GREEN (-6297 7255);
DISPLAY INVISIBLE (-6297 7255);
FORCEPROP 1 LAST PATH I69
J 0
(-6297 7105);
DISPLAY 1.212766 (-6297 7105);
PAINT GREEN (-6297 7105);
DISPLAY INVISIBLE (-6297 7105);
FORCEADD CAPACITOR..2
(-3100 5400);
FORCEPROP 1 LAST $LOCATION C240
J 0
(-3000 5350);
DISPLAY 1.212766 (-3000 5350);
PAINT GREEN (-3000 5350);
FORCEPROP 0 LAST CDS_LOCATION C240
J 0
(-3000 5650);
DISPLAY 1.021277 (-3000 5650);
DISPLAY INVISIBLE (-3000 5650);
FORCEPROP 0 LAST $SEC 1
J 0
(-3000 5650);
DISPLAY 0.680851 (-3000 5650);
PAINT MONO (-3000 5650);
DISPLAY INVISIBLE (-3000 5650);
FORCEPROP 0 LAST CDS_SEC 1
J 0
(-3000 5650);
DISPLAY 1.021277 (-3000 5650);
DISPLAY INVISIBLE (-3000 5650);
FORCEPROP 0 LASTPIN (-3100 5500) $PN 1
R 1
J 0
(-3110 5510);
DISPLAY 0.680851 (-3110 5510);
PAINT MONO (-3110 5510);
FORCEPROP 0 LASTPIN (-3100 5250) $PN 2
R 1
J 2
(-3110 5240);
DISPLAY 0.680851 (-3110 5240);
PAINT MONO (-3110 5240);
FORCEPROP 1 LAST VALUE 22UF
J 0
(-3000 5250);
DISPLAY 1.212766 (-3000 5250);
PAINT GREEN (-3000 5250);
FORCEPROP 0 LAST NO_ASSY TRUE
R 1
J 0
(-3000 5300);
DISPLAY 1.021277 (-3000 5300);
DISPLAY BOTH (-3000 5300);
FORCEPROP 0 LAST VOLTAGE 10V
J 0
(-3000 5600);
DISPLAY 1.021277 (-3000 5600);
FORCEPROP 0 LAST PACKAGE 0805
J 0
(-3000 5500);
DISPLAY 1.021277 (-3000 5500);
FORCEPROP 2 LAST CDS_LIB passive
J 0
(-3100 5400);
DISPLAY INVISIBLE (-3100 5400);
FORCEPROP 1 LAST CDS_LMAN_SYM_OUTLINE -50,0,50,-50
J 0
(-3100 5400);
DISPLAY 0.468085 (-3100 5400);
PAINT GREEN (-3100 5400);
DISPLAY INVISIBLE (-3100 5400);
FORCEPROP 1 LAST CLS_PN G107-0F226-CM
J 0
(-3200 5450);
DISPLAY 1.212766 (-3200 5450);
PAINT GREEN (-3200 5450);
DISPLAY INVISIBLE (-3200 5450);
FORCEPROP 1 LAST TOLERANCE 20%
J 0
(-3250 5500);
DISPLAY 1.212766 (-3250 5500);
PAINT GREEN (-3250 5500);
DISPLAY INVISIBLE (-3250 5500);
FORCEPROP 1 LAST PATH I71
J 0
(-3200 5450);
DISPLAY 1.212766 (-3200 5450);
PAINT GREEN (-3200 5450);
DISPLAY INVISIBLE (-3200 5450);
FORCEADD CAPACITOR..2
(-2650 5400);
FORCEPROP 1 LAST $LOCATION C241
J 0
(-2550 5350);
DISPLAY 1.212766 (-2550 5350);
PAINT GREEN (-2550 5350);
FORCEPROP 0 LAST CDS_LOCATION C241
J 0
(-2550 5650);
DISPLAY 1.021277 (-2550 5650);
DISPLAY INVISIBLE (-2550 5650);
FORCEPROP 0 LAST $SEC 1
J 0
(-2550 5650);
DISPLAY 0.680851 (-2550 5650);
PAINT MONO (-2550 5650);
DISPLAY INVISIBLE (-2550 5650);
FORCEPROP 0 LAST CDS_SEC 1
J 0
(-2550 5650);
DISPLAY 1.021277 (-2550 5650);
DISPLAY INVISIBLE (-2550 5650);
FORCEPROP 0 LASTPIN (-2650 5500) $PN 1
R 1
J 0
(-2660 5510);
DISPLAY 0.680851 (-2660 5510);
PAINT MONO (-2660 5510);
FORCEPROP 0 LASTPIN (-2650 5250) $PN 2
R 1
J 2
(-2660 5240);
DISPLAY 0.680851 (-2660 5240);
PAINT MONO (-2660 5240);
FORCEPROP 1 LAST VALUE 22UF
J 0
(-2550 5250);
DISPLAY 1.212766 (-2550 5250);
PAINT GREEN (-2550 5250);
FORCEPROP 0 LAST VOLTAGE 10V
J 0
(-2550 5600);
DISPLAY 1.021277 (-2550 5600);
FORCEPROP 0 LAST PACKAGE 0805
J 0
(-2550 5500);
DISPLAY 1.021277 (-2550 5500);
FORCEPROP 2 LAST CDS_LIB passive
J 0
(-2650 5400);
DISPLAY INVISIBLE (-2650 5400);
FORCEPROP 1 LAST CDS_LMAN_SYM_OUTLINE -50,0,50,-50
J 0
(-2650 5400);
DISPLAY 0.468085 (-2650 5400);
PAINT GREEN (-2650 5400);
DISPLAY INVISIBLE (-2650 5400);
FORCEPROP 1 LAST CLS_PN G107-0F226-CM
J 0
(-2750 5450);
DISPLAY 1.212766 (-2750 5450);
PAINT GREEN (-2750 5450);
DISPLAY INVISIBLE (-2750 5450);
FORCEPROP 1 LAST TOLERANCE 20%
J 0
(-2800 5500);
DISPLAY 1.212766 (-2800 5500);
PAINT GREEN (-2800 5500);
DISPLAY INVISIBLE (-2800 5500);
FORCEPROP 1 LAST PATH I72
J 0
(-2750 5450);
DISPLAY 1.212766 (-2750 5450);
PAINT GREEN (-2750 5450);
DISPLAY INVISIBLE (-2750 5450);
FORCEADD GND_SG..1
(-2250 4900);
FORCEPROP 3 LASTPIN (-2200 4950) SIG_NAME SG\g
J 0
(-2190 4960);
DISPLAY 0.659574 (-2190 4960);
PAINT MONO (-2190 4960);
DISPLAY INVISIBLE (-2190 4960);
FORCEPROP 1 LAST HDL_POWER SG
J 1
(-2195 4805);
DISPLAY 0.808511 (-2195 4805);
PAINT GREEN (-2195 4805);
FORCEPROP 2 LAST CDS_LIB cls
J 0
(-2250 4900);
DISPLAY INVISIBLE (-2250 4900);
FORCEPROP 1 LAST CDS_LMAN_SYM_OUTLINE 0,0,100,-50
J 0
(-2250 4900);
DISPLAY 0.468085 (-2250 4900);
PAINT GREEN (-2250 4900);
DISPLAY INVISIBLE (-2250 4900);
FORCEPROP 1 LAST BODY_TYPE PLUMBING
J 0
(-2235 4885);
DISPLAY 0.808511 (-2235 4885);
PAINT GREEN (-2235 4885);
DISPLAY INVISIBLE (-2235 4885);
FORCEPROP 1 LAST PATH I73
J 0
(-2215 4900);
DISPLAY 0.808511 (-2215 4900);
PAINT GREEN (-2215 4900);
DISPLAY INVISIBLE (-2215 4900);
FORCEADD CAPACITOR..2
(-2200 5400);
FORCEPROP 1 LAST $LOCATION C243
J 0
(-2100 5350);
DISPLAY 1.212766 (-2100 5350);
PAINT GREEN (-2100 5350);
FORCEPROP 0 LAST CDS_LOCATION C243
J 0
(-2100 5650);
DISPLAY 1.021277 (-2100 5650);
DISPLAY INVISIBLE (-2100 5650);
FORCEPROP 0 LAST $SEC 1
J 0
(-2100 5650);
DISPLAY 0.680851 (-2100 5650);
PAINT MONO (-2100 5650);
DISPLAY INVISIBLE (-2100 5650);
FORCEPROP 0 LAST CDS_SEC 1
J 0
(-2100 5650);
DISPLAY 1.021277 (-2100 5650);
DISPLAY INVISIBLE (-2100 5650);
FORCEPROP 0 LASTPIN (-2200 5500) $PN 1
R 1
J 0
(-2210 5510);
DISPLAY 0.680851 (-2210 5510);
PAINT MONO (-2210 5510);
FORCEPROP 0 LASTPIN (-2200 5250) $PN 2
R 1
J 2
(-2210 5240);
DISPLAY 0.680851 (-2210 5240);
PAINT MONO (-2210 5240);
FORCEPROP 1 LAST VALUE 22UF
J 0
(-2100 5250);
DISPLAY 1.212766 (-2100 5250);
PAINT GREEN (-2100 5250);
FORCEPROP 0 LAST VOLTAGE 10V
J 0
(-2100 5600);
DISPLAY 1.021277 (-2100 5600);
FORCEPROP 0 LAST PACKAGE 0805
J 0
(-2100 5500);
DISPLAY 1.021277 (-2100 5500);
FORCEPROP 1 LAST CLS_PN G107-0F226-CM
J 0
(-2300 5450);
DISPLAY 1.212766 (-2300 5450);
PAINT GREEN (-2300 5450);
DISPLAY INVISIBLE (-2300 5450);
FORCEPROP 1 LAST CDS_LMAN_SYM_OUTLINE -50,0,50,-50
J 0
(-2200 5400);
DISPLAY 0.468085 (-2200 5400);
PAINT GREEN (-2200 5400);
DISPLAY INVISIBLE (-2200 5400);
FORCEPROP 2 LAST CDS_LIB passive
J 0
(-2200 5400);
DISPLAY INVISIBLE (-2200 5400);
FORCEPROP 1 LAST TOLERANCE 20%
J 0
(-2350 5500);
DISPLAY 1.212766 (-2350 5500);
PAINT GREEN (-2350 5500);
DISPLAY INVISIBLE (-2350 5500);
FORCEPROP 1 LAST PATH I74
J 0
(-2300 5450);
DISPLAY 1.212766 (-2300 5450);
PAINT GREEN (-2300 5450);
DISPLAY INVISIBLE (-2300 5450);
FORCEADD VCC..1
(-2250 5950);
FORCEPROP 3 LASTPIN (-2200 5900) SIG_NAME XP3R3V_FPGA\g
J 0
(-2190 5910);
DISPLAY 0.659574 (-2190 5910);
PAINT MONO (-2190 5910);
DISPLAY INVISIBLE (-2190 5910);
FORCEPROP 0 LAST VOLTAGE 3.3V
J 0
(-2500 6100);
DISPLAY 1.021277 (-2500 6100);
DISPLAY BOTH (-2500 6100);
FORCEPROP 1 LAST HDL_POWER XP3R3V_FPGA
J 1
(-2195 6005);
DISPLAY 1.021277 (-2195 6005);
PAINT GREEN (-2195 6005);
FORCEPROP 1 LAST CDS_LMAN_SYM_OUTLINE -250,250,250,-250
J 0
(-2250 5950);
DISPLAY 0.468085 (-2250 5950);
PAINT GREEN (-2250 5950);
DISPLAY INVISIBLE (-2250 5950);
FORCEPROP 2 LAST CDS_LIB cls
J 0
(-2250 5950);
DISPLAY INVISIBLE (-2250 5950);
FORCEPROP 1 LAST BODY_TYPE PLUMBING
J 0
(-2295 5907);
DISPLAY 0.340426 (-2295 5907);
PAINT GREEN (-2295 5907);
DISPLAY INVISIBLE (-2295 5907);
FORCEPROP 1 LAST PATH I75
J 0
(-2215 6040);
DISPLAY 0.808511 (-2215 6040);
PAINT GREEN (-2215 6040);
DISPLAY INVISIBLE (-2215 6040);
FORCEADD NCP45560IMNTWG_H_DFN12..2
(-5700 5050);
FORCEPROP 1 LAST $LOCATION U22
J 2
(-5750 4550);
DISPLAY 1.212766 (-5750 4550);
PAINT GREEN (-5750 4550);
FORCEPROP 0 LAST CDS_LOCATION U22
J 0
(-5750 5100);
DISPLAY 1.021277 (-5750 5100);
DISPLAY INVISIBLE (-5750 5100);
FORCEPROP 0 LAST $SEC 2
J 0
(-5750 5100);
DISPLAY 0.680851 (-5750 5100);
PAINT MONO (-5750 5100);
DISPLAY INVISIBLE (-5750 5100);
FORCEPROP 0 LAST CDS_SEC 2
J 0
(-5750 5100);
DISPLAY 1.021277 (-5750 5100);
DISPLAY INVISIBLE (-5750 5100);
FORCEPROP 0 LASTPIN (-5500 4450) $PN 4
R 1
J 2
(-5510 4440);
DISPLAY 0.680851 (-5510 4440);
PAINT MONO (-5510 4440);
FORCEPROP 0 LASTPIN (-5500 5150) $PN 3
R 1
J 0
(-5510 5160);
DISPLAY 0.680851 (-5510 5160);
PAINT MONO (-5510 5160);
FORCEPROP 1 LAST CLS_PN G222-10203-01
J 2
(-5750 5000);
DISPLAY 1.212766 (-5750 5000);
PAINT GREEN (-5750 5000);
FORCEPROP 1 LAST CDS_LMAN_SYM_OUTLINE 0,0,400,-500
J 0
(-5700 5050);
DISPLAY 0.468085 (-5700 5050);
PAINT GREEN (-5700 5050);
DISPLAY INVISIBLE (-5700 5050);
FORCEPROP 2 LAST CDS_LIB analog
J 0
(-5700 5050);
DISPLAY INVISIBLE (-5700 5050);
FORCEPROP 1 LAST PATH I76
J 2
(-5750 5100);
DISPLAY 1.212766 (-5750 5100);
PAINT GREEN (-5750 5100);
DISPLAY INVISIBLE (-5750 5100);
FORCEADD GND_SG..1
(-5550 4300);
FORCEPROP 3 LASTPIN (-5500 4350) SIG_NAME SG\g
J 0
(-5490 4360);
DISPLAY 0.659574 (-5490 4360);
PAINT MONO (-5490 4360);
DISPLAY INVISIBLE (-5490 4360);
FORCEPROP 1 LAST HDL_POWER SG
J 1
(-5495 4205);
DISPLAY 0.808511 (-5495 4205);
PAINT GREEN (-5495 4205);
FORCEPROP 1 LAST CDS_LMAN_SYM_OUTLINE 0,0,100,-50
J 0
(-5550 4300);
DISPLAY 0.468085 (-5550 4300);
PAINT GREEN (-5550 4300);
DISPLAY INVISIBLE (-5550 4300);
FORCEPROP 2 LAST CDS_LIB cls
J 0
(-5550 4300);
DISPLAY INVISIBLE (-5550 4300);
FORCEPROP 1 LAST BODY_TYPE PLUMBING
J 0
(-5535 4285);
DISPLAY 0.808511 (-5535 4285);
PAINT GREEN (-5535 4285);
DISPLAY INVISIBLE (-5535 4285);
FORCEPROP 1 LAST PATH I77
J 0
(-5515 4300);
DISPLAY 0.808511 (-5515 4300);
PAINT GREEN (-5515 4300);
DISPLAY INVISIBLE (-5515 4300);
FORCEADD CAPACITOR..2
(-5000 4850);
FORCEPROP 1 LAST $LOCATION C235
J 0
(-4850 4800);
DISPLAY 1.212766 (-4850 4800);
PAINT GREEN (-4850 4800);
FORCEPROP 0 LAST CDS_LOCATION C235
J 0
(-4900 5100);
DISPLAY 1.021277 (-4900 5100);
DISPLAY INVISIBLE (-4900 5100);
FORCEPROP 0 LAST $SEC 1
J 0
(-4900 5100);
DISPLAY 0.680851 (-4900 5100);
PAINT MONO (-4900 5100);
DISPLAY INVISIBLE (-4900 5100);
FORCEPROP 0 LAST CDS_SEC 1
J 0
(-4900 5100);
DISPLAY 1.021277 (-4900 5100);
DISPLAY INVISIBLE (-4900 5100);
FORCEPROP 0 LASTPIN (-5000 4950) $PN 1
R 1
J 0
(-5010 4960);
DISPLAY 0.680851 (-5010 4960);
PAINT MONO (-5010 4960);
FORCEPROP 0 LASTPIN (-5000 4700) $PN 2
R 1
J 2
(-5010 4690);
DISPLAY 0.680851 (-5010 4690);
PAINT MONO (-5010 4690);
FORCEPROP 1 LAST VALUE 0.1UF
J 0
(-4900 4700);
DISPLAY 1.212766 (-4900 4700);
PAINT GREEN (-4900 4700);
FORCEPROP 0 LAST PACKAGE 0402
J 0
(-4850 4950);
DISPLAY 1.021277 (-4850 4950);
FORCEPROP 0 LAST VOLTAGE 10V
J 0
(-4850 5050);
DISPLAY 1.021277 (-4850 5050);
FORCEPROP 1 LAST CLS_PN G105-0B104-CK
J 0
(-5100 4900);
DISPLAY 1.212766 (-5100 4900);
PAINT GREEN (-5100 4900);
DISPLAY INVISIBLE (-5100 4900);
FORCEPROP 1 LAST CDS_LMAN_SYM_OUTLINE -50,0,50,-50
J 0
(-5000 4850);
DISPLAY 0.468085 (-5000 4850);
PAINT GREEN (-5000 4850);
DISPLAY INVISIBLE (-5000 4850);
FORCEPROP 2 LAST CDS_LIB passive
J 0
(-5000 4850);
DISPLAY INVISIBLE (-5000 4850);
FORCEPROP 1 LAST TOLERANCE 10%
J 0
(-5150 4950);
DISPLAY 1.212766 (-5150 4950);
PAINT GREEN (-5150 4950);
DISPLAY INVISIBLE (-5150 4950);
FORCEPROP 1 LAST PATH I80
J 0
(-5100 4900);
DISPLAY 1.212766 (-5100 4900);
PAINT GREEN (-5100 4900);
DISPLAY INVISIBLE (-5100 4900);
FORCEADD CAPACITOR..2
(-3650 5400);
FORCEPROP 1 LAST $LOCATION C238
J 0
(-3950 5300);
DISPLAY 1.212766 (-3950 5300);
PAINT GREEN (-3950 5300);
FORCEPROP 0 LAST CDS_LOCATION C238
J 0
(-3550 5650);
DISPLAY 1.021277 (-3550 5650);
DISPLAY INVISIBLE (-3550 5650);
FORCEPROP 0 LAST $SEC 1
J 0
(-3550 5650);
DISPLAY 0.680851 (-3550 5650);
PAINT MONO (-3550 5650);
DISPLAY INVISIBLE (-3550 5650);
FORCEPROP 0 LAST CDS_SEC 1
J 0
(-3550 5650);
DISPLAY 1.021277 (-3550 5650);
DISPLAY INVISIBLE (-3550 5650);
FORCEPROP 0 LASTPIN (-3650 5500) $PN 1
R 1
J 0
(-3660 5510);
DISPLAY 0.680851 (-3660 5510);
PAINT MONO (-3660 5510);
FORCEPROP 0 LASTPIN (-3650 5250) $PN 2
R 1
J 2
(-3660 5240);
DISPLAY 0.680851 (-3660 5240);
PAINT MONO (-3660 5240);
FORCEPROP 1 LAST VALUE 22UF
J 0
(-3900 5450);
DISPLAY 1.212766 (-3900 5450);
PAINT GREEN (-3900 5450);
FORCEPROP 0 LAST NO_ASSY TRUE
R 1
J 0
(-3550 5300);
DISPLAY 1.021277 (-3550 5300);
DISPLAY BOTH (-3550 5300);
FORCEPROP 0 LAST PACKAGE 0805
J 0
(-3900 5600);
DISPLAY 1.021277 (-3900 5600);
FORCEPROP 0 LAST VOLTAGE 10V
J 0
(-3900 5700);
DISPLAY 1.021277 (-3900 5700);
FORCEPROP 1 LAST TOLERANCE 20%
J 0
(-3800 5500);
DISPLAY 1.212766 (-3800 5500);
PAINT GREEN (-3800 5500);
DISPLAY INVISIBLE (-3800 5500);
FORCEPROP 2 LAST CDS_LIB passive
J 0
(-3650 5400);
DISPLAY INVISIBLE (-3650 5400);
FORCEPROP 1 LAST CDS_LMAN_SYM_OUTLINE -50,0,50,-50
J 0
(-3650 5400);
DISPLAY 0.468085 (-3650 5400);
PAINT GREEN (-3650 5400);
DISPLAY INVISIBLE (-3650 5400);
FORCEPROP 1 LAST CLS_PN G107-0F226-CM
J 0
(-3750 5450);
DISPLAY 1.212766 (-3750 5450);
PAINT GREEN (-3750 5450);
DISPLAY INVISIBLE (-3750 5450);
FORCEPROP 1 LAST PATH I81
J 0
(-3750 5450);
DISPLAY 1.212766 (-3750 5450);
PAINT GREEN (-3750 5450);
DISPLAY INVISIBLE (-3750 5450);
FORCEADD NCP45560IMNTWG_H_DFN12..1
(-5850 6700);
FORCEPROP 1 LAST $LOCATION U22
J 0
(-5800 6800);
DISPLAY 1.212766 (-5800 6800);
PAINT GREEN (-5800 6800);
FORCEPROP 0 LAST CDS_LOCATION U22
J 0
(-5800 7100);
DISPLAY 1.021277 (-5800 7100);
DISPLAY INVISIBLE (-5800 7100);
FORCEPROP 0 LAST $SEC 1
J 0
(-5800 7100);
DISPLAY 0.680851 (-5800 7100);
PAINT MONO (-5800 7100);
DISPLAY INVISIBLE (-5800 7100);
FORCEPROP 0 LAST CDS_SEC 1
J 0
(-5800 7100);
DISPLAY 1.021277 (-5800 7100);
DISPLAY INVISIBLE (-5800 7100);
FORCEPROP 0 LASTPIN (-4950 6400) $PN 7
J 0
(-4940 6410);
DISPLAY 0.680851 (-4940 6410);
PAINT MONO (-4940 6410);
FORCEPROP 0 LASTPIN (-5950 6600) $PN 2
J 2
(-5960 6610);
DISPLAY 0.680851 (-5960 6610);
PAINT MONO (-5960 6610);
FORCEPROP 0 LASTPIN (-5950 6400) $PN 6
J 2
(-5960 6410);
DISPLAY 0.680851 (-5960 6410);
PAINT MONO (-5960 6410);
FORCEPROP 0 LASTPIN (-4950 6600) $PN 5
J 0
(-4940 6610);
DISPLAY 0.680851 (-4940 6610);
PAINT MONO (-4940 6610);
FORCEPROP 0 LASTPIN (-5950 6200) $PN 1
J 2
(-5960 6210);
DISPLAY 0.680851 (-5960 6210);
PAINT MONO (-5960 6210);
FORCEPROP 0 LASTPIN (-5950 6100) $PN 13
J 2
(-5960 6110);
DISPLAY 0.680851 (-5960 6110);
PAINT MONO (-5960 6110);
FORCEPROP 0 LASTPIN (-4950 6200) $PN 8
J 0
(-4940 6210);
DISPLAY 0.680851 (-4940 6210);
PAINT MONO (-4940 6210);
FORCEPROP 0 LASTPIN (-4950 6100) $PN 9
J 0
(-4940 6110);
DISPLAY 0.680851 (-4940 6110);
PAINT MONO (-4940 6110);
FORCEPROP 0 LASTPIN (-4950 6000) $PN 10
J 0
(-4940 6010);
DISPLAY 0.680851 (-4940 6010);
PAINT MONO (-4940 6010);
FORCEPROP 0 LASTPIN (-4950 5900) $PN 11
J 0
(-4940 5910);
DISPLAY 0.680851 (-4940 5910);
PAINT MONO (-4940 5910);
FORCEPROP 0 LASTPIN (-4950 5800) $PN 12
J 0
(-4940 5810);
DISPLAY 0.680851 (-4940 5810);
PAINT MONO (-4940 5810);
FORCEPROP 1 LAST CLS_PN G222-10203-01
J 0
(-5800 6900);
DISPLAY 1.212766 (-5800 6900);
PAINT GREEN (-5800 6900);
FORCEPROP 0 LAST PART_NUMBER NCP45560-H
J 0
(-5800 7050);
DISPLAY 1.021277 (-5800 7050);
FORCEPROP 1 LAST CDS_LMAN_SYM_OUTLINE 0,0,800,-1000
J 0
(-5850 6700);
DISPLAY 0.468085 (-5850 6700);
PAINT GREEN (-5850 6700);
DISPLAY INVISIBLE (-5850 6700);
FORCEPROP 2 LAST CDS_LIB analog
J 0
(-5850 6700);
DISPLAY INVISIBLE (-5850 6700);
FORCEPROP 2 LASTPIN (-5950 6400) SIG_NAME UN$515$NCP45560IMNTWGHDFN12$I82$PG
J 0
(-5940 6410);
DISPLAY 0.659574 (-5940 6410);
PAINT MONO (-5940 6410);
DISPLAY INVISIBLE (-5940 6410);
FORCEPROP 1 LAST PATH I82
J 0
(-5800 6750);
DISPLAY 1.212766 (-5800 6750);
PAINT GREEN (-5800 6750);
DISPLAY INVISIBLE (-5800 6750);
FORCEADD VCC..1
(-8650 7550);
FORCEPROP 3 LASTPIN (-8600 7500) SIG_NAME XP3R3V\g
J 0
(-8590 7510);
DISPLAY 0.659574 (-8590 7510);
PAINT MONO (-8590 7510);
DISPLAY INVISIBLE (-8590 7510);
FORCEPROP 1 LAST HDL_POWER XP3R3V
J 1
(-8595 7605);
DISPLAY 1.021277 (-8595 7605);
PAINT GREEN (-8595 7605);
FORCEPROP 0 LAST VOLTAGE 3.3
J 0
(-8850 7650);
DISPLAY 1.021277 (-8850 7650);
DISPLAY BOTH (-8850 7650);
FORCEPROP 2 LAST CDS_LIB cls
J 0
(-8650 7550);
DISPLAY INVISIBLE (-8650 7550);
FORCEPROP 1 LAST CDS_LMAN_SYM_OUTLINE -250,250,250,-250
J 0
(-8650 7550);
DISPLAY 0.468085 (-8650 7550);
PAINT GREEN (-8650 7550);
DISPLAY INVISIBLE (-8650 7550);
FORCEPROP 1 LAST BODY_TYPE PLUMBING
J 0
(-8695 7507);
DISPLAY 0.340426 (-8695 7507);
PAINT GREEN (-8695 7507);
DISPLAY INVISIBLE (-8695 7507);
FORCEPROP 1 LAST PATH I83
J 0
(-8615 7640);
DISPLAY 0.808511 (-8615 7640);
PAINT GREEN (-8615 7640);
DISPLAY INVISIBLE (-8615 7640);
FORCEADD VCC..1
(-5550 5400);
FORCEPROP 3 LASTPIN (-5500 5350) SIG_NAME XP3R3V\g
J 0
(-5490 5360);
DISPLAY 0.659574 (-5490 5360);
PAINT MONO (-5490 5360);
DISPLAY INVISIBLE (-5490 5360);
FORCEPROP 0 LAST VOLTAGE 3.3
J 0
(-5750 5500);
DISPLAY 1.021277 (-5750 5500);
DISPLAY BOTH (-5750 5500);
FORCEPROP 1 LAST HDL_POWER XP3R3V
J 1
(-5495 5455);
DISPLAY 1.021277 (-5495 5455);
PAINT GREEN (-5495 5455);
FORCEPROP 2 LAST CDS_LIB cls
J 0
(-5550 5400);
DISPLAY INVISIBLE (-5550 5400);
FORCEPROP 1 LAST CDS_LMAN_SYM_OUTLINE -250,250,250,-250
J 0
(-5550 5400);
DISPLAY 0.468085 (-5550 5400);
PAINT GREEN (-5550 5400);
DISPLAY INVISIBLE (-5550 5400);
FORCEPROP 1 LAST BODY_TYPE PLUMBING
J 0
(-5595 5357);
DISPLAY 0.340426 (-5595 5357);
PAINT GREEN (-5595 5357);
DISPLAY INVISIBLE (-5595 5357);
FORCEPROP 1 LAST PATH I85
J 0
(-5515 5490);
DISPLAY 0.808511 (-5515 5490);
PAINT GREEN (-5515 5490);
DISPLAY INVISIBLE (-5515 5490);
FORCEADD VCC..1
(-8150 5950);
FORCEPROP 3 LASTPIN (-8100 5900) SIG_NAME XP3R3V\g
J 0
(-8090 5910);
DISPLAY 0.659574 (-8090 5910);
PAINT MONO (-8090 5910);
DISPLAY INVISIBLE (-8090 5910);
FORCEPROP 1 LAST HDL_POWER XP3R3V
J 1
(-8095 6005);
DISPLAY 1.021277 (-8095 6005);
PAINT GREEN (-8095 6005);
FORCEPROP 0 LAST VOLTAGE 3.3
J 0
(-8350 6050);
DISPLAY 1.021277 (-8350 6050);
DISPLAY BOTH (-8350 6050);
FORCEPROP 1 LAST CDS_LMAN_SYM_OUTLINE -250,250,250,-250
J 0
(-8150 5950);
DISPLAY 0.468085 (-8150 5950);
PAINT GREEN (-8150 5950);
DISPLAY INVISIBLE (-8150 5950);
FORCEPROP 2 LAST CDS_LIB cls
J 0
(-8150 5950);
DISPLAY INVISIBLE (-8150 5950);
FORCEPROP 1 LAST BODY_TYPE PLUMBING
J 0
(-8195 5907);
DISPLAY 0.340426 (-8195 5907);
PAINT GREEN (-8195 5907);
DISPLAY INVISIBLE (-8195 5907);
FORCEPROP 1 LAST PATH I86
J 0
(-8115 6040);
DISPLAY 0.808511 (-8115 6040);
PAINT GREEN (-8115 6040);
DISPLAY INVISIBLE (-8115 6040);
FORCEADD CAPACITOR..2
(-9200 6250);
FORCEPROP 1 LAST $LOCATION C229
J 0
(-9100 6150);
DISPLAY 1.212766 (-9100 6150);
PAINT GREEN (-9100 6150);
FORCEPROP 0 LAST CDS_LOCATION C229
J 0
(-9450 6450);
DISPLAY 1.021277 (-9450 6450);
DISPLAY INVISIBLE (-9450 6450);
FORCEPROP 0 LAST $SEC 1
J 0
(-9450 6450);
DISPLAY 0.680851 (-9450 6450);
PAINT MONO (-9450 6450);
DISPLAY INVISIBLE (-9450 6450);
FORCEPROP 0 LAST CDS_SEC 1
J 0
(-9450 6450);
DISPLAY 1.021277 (-9450 6450);
DISPLAY INVISIBLE (-9450 6450);
FORCEPROP 0 LASTPIN (-9200 6350) $PN 1
R 1
J 0
(-9210 6360);
DISPLAY 0.680851 (-9210 6360);
PAINT MONO (-9210 6360);
FORCEPROP 0 LASTPIN (-9200 6100) $PN 2
R 1
J 2
(-9210 6090);
DISPLAY 0.680851 (-9210 6090);
PAINT MONO (-9210 6090);
FORCEPROP 0 LAST VOLTAGE 10V
J 0
(-9100 6450);
DISPLAY 1.021277 (-9100 6450);
FORCEPROP 1 LAST VALUE 0.1UF
J 0
(-9100 6250);
DISPLAY 1.212766 (-9100 6250);
PAINT GREEN (-9100 6250);
FORCEPROP 0 LAST PACKAGE 0402
J 0
(-9100 6350);
DISPLAY 1.021277 (-9100 6350);
FORCEPROP 1 LAST TOLERANCE 10%
J 0
(-9350 6350);
DISPLAY 1.212766 (-9350 6350);
PAINT GREEN (-9350 6350);
DISPLAY INVISIBLE (-9350 6350);
FORCEPROP 1 LAST CLS_PN G105-0B104-CK
J 0
(-9300 6300);
DISPLAY 1.212766 (-9300 6300);
PAINT GREEN (-9300 6300);
DISPLAY INVISIBLE (-9300 6300);
FORCEPROP 1 LAST CDS_LMAN_SYM_OUTLINE -50,0,50,-50
J 0
(-9200 6250);
DISPLAY 0.468085 (-9200 6250);
PAINT GREEN (-9200 6250);
DISPLAY INVISIBLE (-9200 6250);
FORCEPROP 2 LAST CDS_LIB passive
J 0
(-9200 6250);
DISPLAY INVISIBLE (-9200 6250);
FORCEPROP 1 LAST PATH I87
J 0
(-9300 6300);
DISPLAY 1.212766 (-9300 6300);
PAINT GREEN (-9300 6300);
DISPLAY INVISIBLE (-9300 6300);
FORCEADD SHEET_A1..1
(1750 -1800);
FORCEPROP 2 LAST CUSTOM_TXT_CDS <XR_PAGE_TITLE>
J 0
(-13820 9550);
DISPLAY 0.638298 (-13820 9550);
PAINT PINK (-13820 9550);
FORCEPROP 1 LAST CUSTOM_TXT_CDS <DOCNO>
J 0
(-300 -1415);
DISPLAY 0.978723 (-300 -1415);
FORCEPROP 1 LAST CUSTOM_TXT_CDS <CON_PAGE_NUM>
J 0
(-405 -1750);
DISPLAY 0.978723 (-405 -1750);
FORCEPROP 1 LAST CUSTOM_TXT_CDS <DATE>
J 0
(1050 -1625);
DISPLAY 0.978723 (1050 -1625);
FORCEPROP 1 LAST CUSTOM_TXT_CDS <TITLE>
J 1
(-35 -1170);
DISPLAY 0.978723 (-35 -1170);
FORCEPROP 1 LAST CUSTOM_TXT_CDS <DESIGNER>
J 0
(1050 -1200);
DISPLAY 0.978723 (1050 -1200);
FORCEPROP 1 LAST CUSTOM_TXT_CDS <CON_TOTAL_PAGES>
J 0
(-95 -1750);
DISPLAY 0.808511 (-95 -1750);
FORCEPROP 1 LAST CUSTOM_TXT_CDS <ASSY_PN>
J 0
(-300 -1625);
DISPLAY 0.978723 (-300 -1625);
FORCEPROP 1 LAST CUSTOM_TXT_CDS <DOCREV>
J 0
(1050 -1425);
DISPLAY 0.978723 (1050 -1425);
FORCEPROP 1 LAST TITLE XP2R5V_FPGA&XP3R3V_FPGA
J 0
(-1700 -850);
DISPLAY 3.042553 (-1700 -850);
PAINT GREEN (-1700 -850);
FORCEPROP 2 LAST CDS_LIB cls
J 0
(1750 -1800);
DISPLAY INVISIBLE (1750 -1800);
FORCEPROP 1 LAST CDS_LMAN_SYM_OUTLINE -15850,11500,200,-200
J 0
(1750 -1800);
DISPLAY 0.468085 (1750 -1800);
PAINT GREEN (1750 -1800);
DISPLAY INVISIBLE (1750 -1800);
FORCEPROP 1 LAST TITLE XP1R2V_FPGA
J 0
(1750 -1800);
PAINT MONO (1750 -1800);
DISPLAY INVISIBLE (1750 -1800);
FORCEPROP 2 LAST PAGE_BORDER TRUE
J 0
(-8950 6130);
DISPLAY 0.638298 (-8950 6130);
PAINT PINK (-8950 6130);
DISPLAY INVISIBLE (-8950 6130);
FORCEPROP 1 LAST COMMENT_BODY TRUE
J 0
(1760 -1745);
DISPLAY 0.808511 (1760 -1745);
DISPLAY INVISIBLE (1760 -1745);
FORCEPROP 2 LAST CDS_XR_PAGE_TITLE CR-31 : @TIMECARD_LIB.TIMECARD(SCH_1):PAGE31
J 0
(-13820 9550);
DISPLAY 0.638298 (-13820 9550);
PAINT PINK (-13820 9550);
DISPLAY INVISIBLE (-13820 9550);
WIRE 16 -1 (-8600 7500)(-8600 7250);
WIRE 16 -1 (-4400 6250)(-4400 6150);
WIRE 16 -1 (-5750 650)(-5750 750);
WIRE 16 -1 (-6100 7350)(-6100 7100);
WIRE 16 -1 (-5800 -100)(-5800 -150);
WIRE 16 -1 (-8750 300)(-8750 500);
WIRE 16 -1 (-5950 6200)(-6050 6200);
WIRE 16 -1 (-6050 6200)(-6050 6100);
WIRE 16 -1 (-5950 6100)(-6050 6100);
WIRE 16 -1 (-6250 6100)(-6050 6100);
WIRE 16 -1 (-6250 5850)(-6250 6100);
WIRE 16 -1 (-7250 5850)(-6250 5850);
WIRE 16 -1 (-7250 5550)(-7250 5850);
WIRE 16 -1 (-7250 5850)(-7800 5850);
WIRE 16 -1 (-7800 5850)(-8100 5850);
WIRE 16 -1 (-7800 5500)(-7800 5850);
WIRE 16 -1 (-8100 5850)(-8100 5900);
WIRE 16 -1 (-5500 5350)(-5500 5250);
WIRE 16 -1 (-5000 5250)(-5500 5250);
WIRE 16 -1 (-5500 5150)(-5500 5250);
WIRE 16 -1 (-5000 5250)(-5000 4950);
WIRE 16 -1 (-5500 4400)(-5000 4400);
WIRE 16 -1 (-5500 4450)(-5500 4400);
WIRE 16 -1 (-5500 4400)(-5500 4350);
WIRE 16 -1 (-5000 4700)(-5000 4400);
WIRE 16 -1 (-4950 6400)(-4700 6400);
WIRE 16 -1 (-4700 6400)(-4700 6200);
WIRE 16 -1 (-4950 6200)(-4700 6200);
WIRE 16 -1 (-4700 6200)(-4700 6100);
WIRE 16 -1 (-4950 6100)(-4700 6100);
WIRE 16 -1 (-4700 6100)(-4700 6000);
WIRE 16 -1 (-4950 6000)(-4700 6000);
WIRE 16 -1 (-4700 6000)(-4700 5900);
WIRE 16 -1 (-4950 5900)(-4700 5900);
WIRE 16 -1 (-4700 5900)(-4700 5800);
WIRE 16 -1 (-4700 5800)(-4150 5800);
WIRE 16 -1 (-4700 5800)(-4950 5800);
WIRE 16 -1 (-4150 5800)(-3650 5800);
WIRE 16 -1 (-4150 5800)(-4150 5500);
WIRE 16 -1 (-3100 5800)(-3650 5800);
WIRE 16 -1 (-3650 5500)(-3650 5800);
WIRE 16 -1 (-2650 5800)(-3100 5800);
WIRE 16 -1 (-3100 5500)(-3100 5800);
WIRE 16 -1 (-2200 5800)(-2650 5800);
WIRE 16 -1 (-2650 5500)(-2650 5800);
WIRE 16 -1 (-2200 5900)(-2200 5800);
WIRE 16 -1 (-2200 5500)(-2200 5800);
WIRE 16 -1 (-4150 5250)(-4150 5050);
WIRE 16 -1 (-4150 5050)(-3650 5050);
WIRE 16 -1 (-3650 5050)(-3650 5250);
WIRE 16 -1 (-3100 5050)(-3650 5050);
WIRE 16 -1 (-2650 5050)(-3100 5050);
WIRE 16 -1 (-3100 5250)(-3100 5050);
WIRE 16 -1 (-2650 5250)(-2650 5050);
WIRE 16 -1 (-2200 5050)(-2650 5050);
WIRE 16 -1 (-2200 5250)(-2200 5050);
WIRE 16 -1 (-2200 5050)(-2200 4950);
WIRE 16 -1 (-7800 5250)(-7800 4900);
WIRE 16 -1 (-7250 4900)(-7800 4900);
WIRE 16 -1 (-7800 4900)(-7800 4750);
WIRE 16 -1 (-7250 4900)(-7250 5300);
WIRE 16 -1 (-10100 6150)(-10100 5850);
WIRE 16 -1 (-10100 5850)(-9650 5850);
WIRE 16 -1 (-10100 5850)(-10100 5750);
WIRE 16 -1 (-9200 5850)(-9650 5850);
WIRE 16 -1 (-9650 6100)(-9650 5850);
WIRE 16 -1 (-9200 6100)(-9200 5850);
WIRE 16 -1 (-10750 1600)(-11200 1600);
WIRE 16 -1 (-10750 1550)(-10750 1600);
WIRE 16 -1 (-10750 1700)(-10750 1600);
WIRE 16 -1 (-11200 1600)(-11200 1700);
WIRE 16 -1 (-6950 1550)(-6600 1550);
WIRE 16 -1 (-6600 1550)(-6600 1650);
WIRE 16 -1 (-6950 1650)(-6600 1650);
WIRE 16 -1 (-6600 2150)(-6600 1650);
WIRE 16 -1 (-6600 2150)(-4450 2150);
WIRE 16 -1 (-4450 2150)(-3800 2150);
WIRE 16 -1 (-4450 1850)(-4450 2150);
WIRE 16 -1 (-3200 2150)(-3800 2150);
WIRE 16 -1 (-3800 1850)(-3800 2150);
WIRE 16 -1 (-3200 1850)(-3200 2150);
WIRE 16 -1 (-2350 2150)(-3200 2150);
WIRE 16 -1 (-2350 2250)(-2350 2150);
WIRE 16 -1 (-3800 1600)(-3800 1350);
WIRE 16 -1 (-3800 1350)(-3200 1350);
WIRE 16 -1 (-3200 1600)(-3200 1350);
WIRE 16 -1 (-3200 1150)(-3200 1350);
WIRE 16 -1 (-4400 950)(-4400 800);
WIRE 16 -1 (-4400 800)(-4150 800);
WIRE 16 -1 (-4150 800)(-4150 950);
WIRE 16 -1 (-4150 750)(-4150 800);
WIRE 16 -1 (-6950 950)(-6650 950);
WIRE 16 -1 (-6650 950)(-6650 850);
WIRE 16 -1 (-6650 150)(-6650 850);
WIRE 16 -1 (-6950 850)(-6650 850);
WIRE 16 -1 (-8850 1700)(-8850 1550);
WIRE 16 -1 (-8850 1550)(-8850 1450);
WIRE 16 -1 (-9300 1550)(-8850 1550);
WIRE 16 -1 (-9300 1700)(-9300 1550);
WIRE 16 -1 (-9250 650)(-9250 450);
WIRE 16 -1 (-9250 450)(-9800 450);
WIRE 16 -1 (-9800 450)(-9800 700);
WIRE 16 -1 (-10150 450)(-9800 450);
WIRE 16 -1 (-10150 350)(-10150 450);
WIRE 16 -1 (-10150 650)(-10150 450);
WIRE 16 -1 (-11300 2250)(-11300 2150);
WIRE 16 -1 (-11200 2150)(-11300 2150);
WIRE 16 -1 (-10750 2150)(-11200 2150);
WIRE 16 -1 (-11200 2150)(-11200 1950);
WIRE 16 -1 (-10650 2150)(-10750 2150);
WIRE 16 -1 (-10750 2150)(-10750 1950);
WIRE 16 273 (-13450 3550)(800 3550);
WIRE 16 -1 (-10750 1150)(-10150 1150);
WIRE 16 -1 (-10150 1150)(-9800 1150);
WIRE 16 -1 (-10150 900)(-10150 1150);
WIRE 16 -1 (-9800 950)(-9800 1150);
WIRE 16 -1 (-9750 1150)(-9800 1150);
WIRE 16 -1 (-9750 1150)(-9250 1150);
WIRE 16 -1 (-9750 1550)(-9750 1150);
WIRE 16 -1 (-8050 1150)(-9250 1150);
WIRE 16 -1 (-9250 900)(-9250 1150);
WIRE 16 -1 (-8750 750)(-8750 950);
WIRE 16 -1 (-8750 950)(-8050 950);
WIRE 16 -1 (-10250 2150)(-9750 2150);
WIRE 16 -1 (-9750 2150)(-9300 2150);
WIRE 16 -1 (-9750 1800)(-9750 2150);
WIRE 16 -1 (-9300 1950)(-9300 2150);
WIRE 16 -1 (-8850 2150)(-9300 2150);
WIRE 16 -1 (-8850 1950)(-8850 2150);
WIRE 16 -1 (-8400 2150)(-8850 2150);
WIRE 16 -1 (-8400 2150)(-8400 1650);
WIRE 16 -1 (-8050 1650)(-8400 1650);
WIRE 16 -1 (-8400 1550)(-8400 1650);
WIRE 16 -1 (-8050 1550)(-8400 1550);
WIRE 16 -1 (-4400 6600)(-4400 6500);
WIRE 16 -1 (-4950 6600)(-4400 6600);
FORCEPROP 2 LAST SIG_NAME XP3R3V_FPGA_SR
J 0
(-4860 6660);
DISPLAY 1.021277 (-4860 6660);
WIRE 16 -1 (-7900 6400)(-6750 6400);
FORCEPROP 2 LAST SIG_NAME FPGA_CFG_INIT_N
J 0
(-7860 6410);
DISPLAY 1.021277 (-7860 6410);
WIRE 16 -1 (-4900 250)(-3700 250);
FORCEPROP 2 LAST SIG_NAME FPGA_CFG_INIT_N
J 0
(-4510 260);
DISPLAY 1.021277 (-4510 260);
WIRE 16 -1 (-5750 400)(-5750 250);
WIRE 16 -1 (-5150 250)(-5750 250);
WIRE 16 -1 (-5750 250)(-5800 250);
WIRE 16 -1 (-5800 150)(-5800 250);
WIRE 16 -1 (-6350 250)(-5800 250);
WIRE 16 -1 (-6350 250)(-6350 1150);
WIRE 16 -1 (-6350 1150)(-6950 1150);
WIRE 16 -1 (-4150 1200)(-4150 1350);
WIRE 16 -1 (-4150 1350)(-4400 1350);
WIRE 16 -1 (-4400 1200)(-4400 1350);
WIRE 16 -1 (-4400 1350)(-4450 1350);
WIRE 16 -1 (-6950 1350)(-4450 1350);
WIRE 16 -1 (-4450 1600)(-4450 1350);
WIRE 16 -1 (-10550 6600)(-10100 6600);
WIRE 16 -1 (-10100 6600)(-9650 6600);
WIRE 16 -1 (-10100 6400)(-10100 6600);
WIRE 16 -1 (-9200 6600)(-9650 6600);
WIRE 16 -1 (-9650 6600)(-9650 6350);
WIRE 16 -1 (-8600 6600)(-9200 6600);
WIRE 16 -1 (-9200 6350)(-9200 6600);
WIRE 16 -1 (-5950 6600)(-8600 6600);
FORCEPROP 2 LAST SIG_NAME XP3R3V_FPGA_EN_R
J 0
(-7210 6610);
DISPLAY 1.021277 (-7210 6610);
WIRE 16 -1 (-8600 7000)(-8600 6600);
WIRE 16 -1 (-11850 6600)(-10800 6600);
FORCEPROP 2 LAST SIG_NAME XP1R8V_FPGA_PG
J 0
(-11760 6610);
DISPLAY 1.021277 (-11760 6610);
WIRE 16 -1 (-12100 1150)(-11000 1150);
FORCEPROP 2 LAST SIG_NAME XP1R8V_FPGA_PG
J 0
(-12060 1160);
DISPLAY 1.021277 (-12060 1160);
WIRE 16 -1 (-6500 6400)(-6100 6400);
WIRE 16 -1 (-6100 6850)(-6100 6400);
WIRE 16 -1 (-5950 6400)(-6100 6400);
WIRE 8 -1 (900 2200)(-400 2200);
WIRE 8 -1 (900 2200)(900 2050);
WIRE 8 -1 (-400 2050)(-400 2200);
WIRE 8 -1 (-400 2200)(-1250 2200);
WIRE 8 -1 (-1250 2200)(-1250 2050);
WIRE 8 -1 (-1250 2050)(-400 2050);
WIRE 8 -1 (-400 2050)(900 2050);
WIRE 8 -1 (-400 1900)(-400 2050);
WIRE 8 -1 (900 2050)(900 1900);
WIRE 8 -1 (-400 1900)(900 1900);
WIRE 8 -1 (900 1750)(900 1900);
WIRE 8 -1 (-1250 1900)(-400 1900);
WIRE 8 -1 (-400 1750)(-400 1900);
WIRE 8 -1 (-1250 2050)(-1250 1900);
WIRE 8 -1 (-1250 1750)(-1250 1900);
WIRE 8 -1 (-1250 1750)(-400 1750);
WIRE 8 -1 (-400 1750)(900 1750);
WIRE 8 -1 (-400 1600)(-400 1750);
WIRE 8 -1 (900 1600)(900 1750);
WIRE 8 -1 (-400 1600)(900 1600);
WIRE 8 -1 (900 1450)(900 1600);
WIRE 8 -1 (-1250 1600)(-400 1600);
WIRE 8 -1 (-400 1450)(-400 1600);
WIRE 8 -1 (-1250 1600)(-1250 1750);
WIRE 8 -1 (-1250 1450)(-1250 1600);
WIRE 8 -1 (-1250 1450)(-400 1450);
WIRE 8 -1 (-400 1450)(900 1450);
WIRE 8 -1 (-500 5700)(250 5700);
WIRE 8 -1 (-500 5700)(-500 5500);
WIRE 8 -1 (-1150 5700)(-500 5700);
WIRE 8 -1 (250 5700)(250 5500);
WIRE 8 -1 (250 5500)(250 5300);
WIRE 8 -1 (-500 5500)(250 5500);
WIRE 8 -1 (-1150 5700)(-1150 5500);
WIRE 8 -1 (-500 5500)(-500 5300);
WIRE 8 -1 (-1150 5500)(-500 5500);
WIRE 8 -1 (-1150 5500)(-1150 5300);
WIRE 8 -1 (-500 5300)(250 5300);
WIRE 8 -1 (-1150 5300)(-500 5300);
WIRE 8 -1 (-500 5300)(-500 5100);
WIRE 8 -1 (250 5300)(250 5100);
WIRE 8 -1 (-500 5100)(250 5100);
WIRE 8 -1 (-1150 5100)(-500 5100);
WIRE 8 -1 (-1150 5300)(-1150 5100);
DOT 1 (-3200 1350);
DOT 1 (-5750 250);
DOT 1 (-8850 1550);
DOT 1 (-2200 5050);
DOT 1 (-10750 1600);
DOT 1 (-11200 2150);
DOT 1 (-10750 2150);
DOT 1 (-9750 1150);
DOT 1 (-9750 2150);
DOT 1 (-9300 2150);
DOT 1 (-8850 2150);
DOT 1 (-8400 1650);
DOT 1 (-6650 850);
DOT 1 (-6600 1650);
DOT 1 (-5800 250);
DOT 1 (-4150 800);
DOT 1 (-4450 1350);
DOT 1 (-4400 1350);
DOT 1 (-4450 2150);
DOT 1 (-3800 2150);
DOT 1 (-1250 1600);
DOT 1 (-1250 1750);
DOT 1 (-1250 1900);
DOT 1 (-1250 2050);
DOT 1 (-400 1600);
DOT 1 (-400 1450);
DOT 1 (-400 1750);
DOT 1 (-400 1900);
DOT 1 (-400 2050);
DOT 1 (-400 2200);
DOT 1 (900 1600);
DOT 1 (900 1900);
DOT 1 (900 1750);
DOT 1 (900 2050);
DOT 1 (-1150 5500);
DOT 1 (-1150 5300);
DOT 1 (-500 5100);
DOT 1 (-500 5300);
DOT 1 (-500 5500);
DOT 1 (-500 5700);
DOT 1 (250 5500);
DOT 1 (250 5300);
DOT 1 (-3200 2150);
DOT 1 (-9250 1150);
DOT 1 (-9800 1150);
DOT 1 (-10150 1150);
DOT 1 (-9800 450);
DOT 1 (-10150 450);
DOT 1 (-2200 5800);
DOT 1 (-2650 5800);
DOT 1 (-2650 5050);
DOT 1 (-3100 5800);
DOT 1 (-3650 5800);
DOT 1 (-3100 5050);
DOT 1 (-3650 5050);
DOT 1 (-4700 6200);
DOT 1 (-4150 5800);
DOT 1 (-4700 6100);
DOT 1 (-4700 6000);
DOT 1 (-4700 5900);
DOT 1 (-4700 5800);
DOT 1 (-5500 5250);
DOT 1 (-5500 4400);
DOT 1 (-6100 6400);
DOT 1 (-6050 6100);
DOT 1 (-7250 5850);
DOT 1 (-7800 5850);
DOT 1 (-7800 4900);
DOT 1 (-8600 6600);
DOT 1 (-9200 6600);
DOT 1 (-9650 6600);
DOT 1 (-10100 6600);
DOT 1 (-9650 5850);
DOT 1 (-10100 5850);
FORCENOTE
XP2R5V_FPGA
(-7750 2950) 0;
DISPLAY LEFT (-7750 2950);
DISPLAY 4.914894 (-7750 2950);
FORCENOTE
SS: 2.5MS
(-8250 600) 0;
DISPLAY LEFT (-8250 600);
DISPLAY 1.595745 (-8250 600);
FORCENOTE
VFB=0.5V
(-4950 1450) 0;
DISPLAY LEFT (-4950 1450);
DISPLAY 1.021277 (-4950 1450);
FORCENOTE
RTOP
(-4750 1750) 0;
DISPLAY LEFT (-4750 1750);
DISPLAY 1.021277 (-4750 1750);
FORCENOTE
0.042A
(-2950 2200) 0;
DISPLAY LEFT (-2950 2200);
DISPLAY 1.595745 (-2950 2200);
FORCENOTE
VOUT
(-1000 1800) 0;
DISPLAY LEFT (-1000 1800);
DISPLAY 1.595745 (-1000 1800);
FORCENOTE
OCP
(-1000 1500) 0;
DISPLAY LEFT (-1000 1500);
DISPLAY 1.595745 (-1000 1500);
FORCENOTE
PARAMETERS
(-1200 2100) 0;
DISPLAY LEFT (-1200 2100);
DISPLAY 1.595745 (-1200 2100);
FORCENOTE
VIN
(-1000 1950) 0;
DISPLAY LEFT (-1000 1950);
DISPLAY 1.595745 (-1000 1950);
FORCENOTE
IOUT
(-1000 1650) 0;
DISPLAY LEFT (-1000 1650);
DISPLAY 1.595745 (-1000 1650);
FORCENOTE
VALUE(TYP)
(-150 2100) 0;
DISPLAY LEFT (-150 2100);
DISPLAY 1.595745 (-150 2100);
FORCENOTE
3.3V
(-150 1950) 0;
DISPLAY LEFT (-150 1950);
DISPLAY 1.595745 (-150 1950);
FORCENOTE
XP2R5V_FPGA
(-1200 2250) 0;
DISPLAY LEFT (-1200 2250);
DISPLAY 3.148936 (-1200 2250);
PAINT VIOLET (-1200 2250);
FORCENOTE
0.042A
(-150 1650) 0;
DISPLAY LEFT (-150 1650);
DISPLAY 1.595745 (-150 1650);
FORCENOTE
1.75A
(-150 1500) 0;
DISPLAY LEFT (-150 1500);
DISPLAY 1.595745 (-150 1500);
FORCENOTE
2.5V
(-150 1800) 0;
DISPLAY LEFT (-150 1800);
DISPLAY 1.595745 (-150 1800);
FORCENOTE
XP3R3V_FPGA
(-1150 5800) 0;
DISPLAY LEFT (-1150 5800);
DISPLAY 2.000000 (-1150 5800);
PAINT VIOLET (-1150 5800);
FORCENOTE
IMAX
(-900 5150) 0;
DISPLAY LEFT (-900 5150);
DISPLAY 1.595745 (-900 5150);
FORCENOTE
VIN
(-900 5550) 0;
DISPLAY LEFT (-900 5550);
DISPLAY 1.595745 (-900 5550);
FORCENOTE
RDSON
(-900 5350) 0;
DISPLAY LEFT (-900 5350);
DISPLAY 1.595745 (-900 5350);
FORCENOTE
3V3
(-250 5550) 0;
DISPLAY LEFT (-250 5550);
DISPLAY 1.595745 (-250 5550);
FORCENOTE
4.3MOHM
(-350 5350) 0;
DISPLAY LEFT (-350 5350);
DISPLAY 1.595745 (-350 5350);
FORCENOTE
0.1A
(-250 5150) 0;
DISPLAY LEFT (-250 5150);
DISPLAY 1.595745 (-250 5150);
FORCENOTE
XP3R3V_FPGA
(-7300 8400) 0;
DISPLAY LEFT (-7300 8400);
DISPLAY 4.914894 (-7300 8400);
FORCENOTE
VOUT=(RTOP/RBOTTOM+1)*VFB
(-5750 1600) 0;
DISPLAY LEFT (-5750 1600);
DISPLAY 1.021277 (-5750 1600);
QUIT
